PARTS LIST

78.10421.2FL       C402H22                      C1
78.10521.2BL       C603H36                      C2
78.10521.2BL       C603H36                      C8
078.10521.08F1     C402-TO0D2H24                C9
078.10521.08F1     C402-TO0D2H24                C10
078.10521.08F1     C402-TO0D2H24                C11
078.10521.08F1     C402-TO0D2H24                C12
78.10521.2BL       C603H36                      C13
78.10224.2FL       C402H22                      C14
78.10521.2BL       C603H36                      C15
78.10521.2BL       C603H36                      C16
78.18034.1FL       C402H22                      C17
78.10521.2BL       C603H36                      C18
78.10521.2BL       C603H36                      C19
78.18034.1FL       C402H22                      C20
78.10521.2BL       C603H36                      C21
78.10521.2BL       C603H36                      C22
78.22522.21L       C805H54                      C25
78.10521.2BL       C603H36                      C26
78.10421.2FL       C402H22                      C27
78.22522.21L       C805H54                      C28
78.22522.21L       C805H54                      C29
78.10421.2FL       C402H22                      C30
78.10521.2BL       C603H36                      C31
78.10421.2FL       C402H22                      C32
78.10421.2FL       C402H22                      C33
78.10421.2FL       C402H22                      C34
078.10521.08F1     C402-TO0D2H24                C35
78.10421.2FL       C402H22                      C36
78.10421.2FL       C402H22                      C37
78.10421.2FL       C402H22                      C38
78.10421.2FL       C402H22                      C39
78.10421.2FL       C402H22                      C40
78.10421.2FL       C402H22                      C41
78.10421.2FL       C402H22                      C44
78.10421.2FL       C402H22                      C49
78.10421.2FL       C402H22                      C50
78.10421.2FL       C402H22                      C51
78.10421.2FL       C402H22                      C52
78.10322.2FL       C402H22                      C53
78.10521.2BL       C603H36                      C54
78.10421.2FL       C402H22                      C55
78.10521.2BL       C603H36                      C56
78.10620.21L       C805H58                      C57
78.10521.2BL       C603H36                      C58
78.10521.2BL       C603H36                      C59
78.10521.2BL       C603H36                      C60
78.10521.2BL       C603H36                      C61
78.10521.2BL       C603H36                      C62
078.47522.0211     C805H58                      C63
78.10521.2BL       C603H36                      C64
78.10521.2BL       C603H36                      C65
78.10421.2FL       C402H22                      C66
78.10421.2FL       C402H22                      C67
78.10421.2FL       C402H22                      C68
78.10421.2FL       C402H22                      C69
78.10421.2FL       C402H22                      C70
78.10421.2FL       C402H22                      C71
78.10421.2FL       C402H22                      C72
78.10421.2FL       C402H22                      C73
78.10421.2FL       C402H22                      C74
78.10421.2FL       C402H22                      C75
78.10322.2FL       C402H22                      C76
78.10421.2FL       C402H22                      C78
78.10421.2FL       C402H22                      C79
78.10421.2FL       C402H22                      C80
078.47522.0211     C805H58                      C81
78.33034.1FL       C402H22                      C82
78.10521.2BL       C603H36                      C83
78.10421.2FL       C402H22                      C84
78.10421.2FL       C402H22                      C85
78.10421.2FL       C402H22                      C86
78.10521.2BL       C603H36                      C87
78.10134.1FL       C402H22                      C88
078.47522.0211     C805H58                      C89
78.10521.2BL       C603H36                      C90
78.10134.1FL       C402H22                      C91
78.10521.2BL       C603H36                      C92
78.10421.2FL       C402H22                      C93
78.10134.1FL       C402H22                      C94
78.10521.2BL       C603H36                      C95
78.10134.1FL       C402H22                      C96
78.10521.2BL       C603H36                      C97
78.10521.2BL       C603H36                      C98
78.10521.2BL       C603H36                      C99
78.10521.2BL       C603H36                      C100
78.10521.2BL       C603H36                      C101
78.10521.2BL       C603H36                      C102
78.10421.2FL       C402H22                      C103
078.10620.08B1     C603H40                      C104
78.10134.1FL       C402H22                      C105
078.47522.0211     C805H58                      C106
78.10521.2BL       C603H36                      C107
78.10521.2BL       C603H36                      C108
78.10521.2BL       C603H36                      C109
78.10521.2BL       C603H36                      C110
78.10521.2BL       C603H36                      C113
78.10521.2BL       C603H36                      C114
078.10620.08B1     C603H40                      C115
078.47522.0211     C805H58                      C116
78.10422.2FL       C402H22                      C117
78.10422.2FL       C402H22                      C118
78.10422.2FL       C402H22                      C119
78.10422.2FL       C402H22                      C120
78.10422.2FL       C402H22                      C121
78.10422.2FL       C402H22                      C122
78.10422.2FL       C402H22                      C123
78.10422.2FL       C402H22                      C124
78.10422.2FL       C402H22                      C125
78.10421.2FL       C402H22                      C126
78.10421.2FL       C402H22                      C127
78.10522.2BL       C603H36                      C128
78.10224.2FL       C402H22                      C129
78.10421.2FL       C402H22                      C130
78.10322.2FL       C402H22                      C131
78.22621.82L       C1206H75                     C132
78.15322.2FL       C402H22                      C133
78.15322.2FL       C402H22                      C134
78.10421.2FL       C402H22                      C135
78.10421.2FL       C402H22                      C136
78.10421.2FL       C402H22                      C137
78.10422.2FL       C402H22                      C138
78.10424.2BL       C603H36                      C139
78.10421.2FL       C402H22                      C141
78.10521.2BL       C603H36                      C144
78.10521.2BL       C603H36                      C145
78.33324.2BL       C603H36                      C146
78.10521.2BL       C603H36                      C147
78.10424.2BL       C603H36                      C148
78.10424.2BL       C603H36                      C149
78.10424.2BL       C603H36                      C150
078.10621.0211     C805H58                      C151
078.10621.0211     C805H58                      C152
078.10621.0211     C805H58                      C153
078.10621.0211     C805H58                      C154
078.10621.0211     C805H58                      C155
78.10521.2BL       C603H36                      C156
078.47522.0211     C805H58                      C157
78.10424.2BL       C603H36                      C158
78.22224.2FL       C402H22                      C159
78.10424.2BL       C603H36                      C160
78.10521.2BL       C603H36                      C161
78.10224.2FL       C402H22                      C162
078.68034.C1F1     C402H22                      C163
078.10621.0211     C805H58                      C164
078.10621.0211     C805H58                      C165
078.10621.0211     C805H58                      C166
77.21071.02L       CT7343H79                    C167
77.21571.18L       CT7343H119                   C168
78.10421.2FL       C402H22                      C169
078.10621.0211     C805H58                      C170
078.10621.0211     C805H58                      C171
78.10620.21L       C805H58                      C172
078.10621.0211     C805H58                      C173
78.10620.21L       C805H58                      C174
077.51571.0001     CT7343H83                    C175
078.10621.0211     C805H58                      C176
078.10621.0211     C805H58                      C177
78.10424.2BL       C603H36                      C178
078.47522.0211     C805H58                      C179
78.22224.2FL       C402H22                      C180
78.10422.2FL       C402H22                      C181
78.10521.2BL       C603H36                      C182
78.10224.2FL       C402H22                      C183
078.68034.C1F1     C402H22                      C184
78.10421.2FL       C402H22                      C185
78.47422.2BL       C603H36                      C186
78.10620.21L       C805H58                      C187
78.10620.21L       C805H58                      C188
78.10422.2FL       C402H22                      C189
78.10224.2FL       C402H22                      C190
78.10620.21L       C805H58                      C191
78.10620.21L       C805H58                      C192
78.10620.21L       C805H58                      C193
78.10620.21L       C805H58                      C194
78.10421.2FL       C402H22                      C195
78.47124.2FL       C402H22                      C196
78.10521.2BL       C603H36                      C197
78.10421.2FL       C402H22                      C198
78.10620.21L       C805H58                      C199
78.10620.21L       C805H58                      C200
78.10421.2FL       C402H22                      C201
78.10521.2BL       C603H36                      C202
78.10421.2FL       C402H22                      C203
078.10621.0211     C805H58                      C204
078.10621.0211     C805H58                      C205
78.10134.1FL       C402H22                      C206
78.10424.2BL       C603H36                      C207
78.33224.2FL       C402H22                      C208
78.10521.2BL       C603H36                      C209
78.22224.2FL       C402H22                      C210
78.10424.2BL       C603H36                      C211
78.10224.2FL       C402H22                      C212
78.10521.2BL       C603H36                      C213
78.10421.2FL       C402H22                      C214
78.10620.21L       C805H58                      C215
78.10620.21L       C805H58                      C216
78.10620.21L       C805H58                      C217
78.10620.21L       C805H58                      C218
78.47422.2BL       C603H36                      C219
78.10620.21L       C805H58                      C220
78.10422.2FL       C402H22                      C221
78.10224.2FL       C402H22                      C222
78.10620.21L       C805H58                      C223
78.10620.21L       C805H58                      C224
78.10620.21L       C805H58                      C225
78.10620.21L       C805H58                      C226
78.10421.2FL       C402H22                      C227
78.47124.2FL       C402H22                      C228
78.10521.2BL       C603H36                      C229
78.10421.2FL       C402H22                      C230
78.10620.21L       C805H58                      C231
78.10620.21L       C805H58                      C232
78.10421.2FL       C402H22                      C233
78.10224.2FL       C402H22                      C234
78.10620.21L       C805H58                      C235
78.10620.21L       C805H58                      C236
78.10620.21L       C805H58                      C237
78.10620.21L       C805H58                      C238
78.10421.2FL       C402H22                      C239
78.47124.2FL       C402H22                      C240
78.10521.2BL       C603H36                      C241
78.10421.2FL       C402H22                      C242
78.10620.21L       C805H58                      C243
78.10620.21L       C805H58                      C244
78.10421.2FL       C402H22                      C245
78.10224.2FL       C402H22                      C246
78.10620.21L       C805H58                      C247
78.10620.21L       C805H58                      C248
78.10620.21L       C805H58                      C249
78.10620.21L       C805H58                      C250
78.10421.2FL       C402H22                      C251
78.47124.2FL       C402H22                      C252
78.10521.2BL       C603H36                      C253
78.10421.2FL       C402H22                      C254
78.10620.21L       C805H58                      C255
78.10620.21L       C805H58                      C256
78.10421.2FL       C402H22                      C257
78.22620.22L       C1206H71                     C258
78.22620.22L       C1206H71                     C259
78.22620.22L       C1206H71                     C260
78.22620.22L       C1206H71                     C261
78.68224.2FL       C402H22                      C262
78.10424.2BL       C603H36                      C263
78.22620.22L       C1206H71                     C264
78.22620.22L       C1206H71                     C265
78.22620.22L       C1206H71                     C266
78.10522.2BL       C603H36                      C267
78.22620.22L       C1206H71                     C268
078.10621.0211     C805H58                      C269
078.10621.0211     C805H58                      C270
078.10621.0211     C805H58                      C271
078.10621.0211     C805H58                      C272
078.10621.0211     C805H58                      C273
078.10621.0211     C805H58                      C274
078.10621.0211     C805H58                      C275
78.47222.2FL       C402H24                      C276
78.10522.2BL       C603H36                      C277
78.10522.2BL       C603H36                      C278
78.68224.2FL       C402H22                      C279
78.10523.5FL       C402H22                      C280
78.22124.2FL       C402H22                      C281
78.10522.2BL       C603H36                      C282
78.22620.22L       C1206H71                     C283
78.10322.2FL       C402H22                      C284
78.10424.2BL       C603H36                      C285
78.33421.2BL       C603H36                      C286
78.10224.2FL       C402H22                      C287
78.10424.2BL       C603H36                      C288
78.22423.5SL       C0201H13                     C289
78.22423.5SL       C0201H13                     C290
78.22423.5SL       C0201H13                     C291
78.22423.5SL       C0201H13                     C292
78.22423.5SL       C0201H13                     C293
78.22423.5SL       C0201H13                     C294
78.22423.5SL       C0201H13                     C295
78.22423.5SL       C0201H13                     C296
78.22423.5SL       C0201H13                     C297
78.22423.5SL       C0201H13                     C298
78.22423.5SL       C0201H13                     C299
78.22423.5SL       C0201H13                     C300
78.22423.5SL       C0201H13                     C301
78.22423.5SL       C0201H13                     C302
78.22423.5SL       C0201H13                     C303
78.22423.5SL       C0201H13                     C304
78.12034.1FL       C402H24                      C305
78.12034.1FL       C402H24                      C306
078.10321.02S1     C0201H13                     C307
078.10321.02S1     C0201H13                     C308
078.10321.02S1     C0201H13                     C309
078.10321.02S1     C0201H13                     C310
078.10321.02S1     C0201H13                     C311
078.10321.02S1     C0201H13                     C312
078.10321.02S1     C0201H13                     C313
078.10321.02S1     C0201H13                     C314
078.10321.02S1     C0201H13                     C315
078.10321.02S1     C0201H13                     C316
078.10321.02S1     C0201H13                     C317
078.10321.02S1     C0201H13                     C318
078.10321.02S1     C0201H13                     C319
078.10321.02S1     C0201H13                     C320
078.10321.02S1     C0201H13                     C321
078.10321.02S1     C0201H13                     C322
78.10421.2FL       C402H22                      C323
79.47719.2BL       CT7343H83                    C324
77.21571.18L       CT7343H119                   C325
78.10421.2FL       C402H22                      C327
78.10421.2FL       C402H22                      C328
78.10421.2FL       C402H22                      C329
078.22610.08B1     C603H40                      C330
78.10620.21L       C805H58                      C331
78.10620.21L       C805H58                      C332
78.10420.50L       C0201H13                     C333
078.22610.08B1     C603H40                      C334
78.10620.21L       C805H58                      C335
78.10420.50L       C0201H13                     C336
78.10510.5SL       C0201H14                     C337
078.22610.08B1     C603H40                      C338
78.10620.21L       C805H58                      C339
78.10510.5SL       C0201H14                     C340
78.10420.50L       C0201H13                     C341
078.22610.08B1     C603H40                      C342
78.10620.21L       C805H58                      C343
78.10510.5SL       C0201H14                     C344
78.10420.50L       C0201H13                     C345
078.22610.08B1     C603H40                      C346
78.10620.21L       C805H58                      C347
78.10510.5SL       C0201H14                     C348
78.10420.50L       C0201H13                     C349
078.22610.08B1     C603H40                      C350
78.10620.21L       C805H58                      C351
78.10510.5SL       C0201H14                     C352
78.10420.50L       C0201H13                     C353
78.10420.50L       C0201H13                     C354
78.10420.50L       C0201H13                     C355
078.22610.08B1     C603H40                      C356
78.10620.21L       C805H58                      C357
78.10510.5SL       C0201H14                     C358
78.10420.50L       C0201H13                     C359
78.10420.50L       C0201H13                     C360
78.10420.50L       C0201H13                     C361
78.10710.52L       C1206H71                     C362
078.22610.08B1     C603H40                      C363
78.10510.5SL       C0201H14                     C364
78.10420.50L       C0201H13                     C365
78.10420.50L       C0201H13                     C366
78.10420.50L       C0201H13                     C367
78.10420.50L       C0201H13                     C368
78.10420.50L       C0201H13                     C369
78.10420.50L       C0201H13                     C370
78.10420.50L       C0201H13                     C371
78.10420.50L       C0201H13                     C372
78.10710.52L       C1206H71                     C373
78.10710.52L       C1206H71                     C374
78.10510.5SL       C0201H14                     C375
78.10420.50L       C0201H13                     C376
78.10420.50L       C0201H13                     C377
78.10420.50L       C0201H13                     C378
78.10420.50L       C0201H13                     C379
78.10420.50L       C0201H13                     C380
78.10420.50L       C0201H13                     C381
78.10420.50L       C0201H13                     C382
78.10420.50L       C0201H13                     C383
78.10620.21L       C805H58                      C384
78.10620.21L       C805H58                      C385
78.10620.21L       C805H58                      C386
78.10620.21L       C805H58                      C387
78.10620.21L       C805H58                      C388
78.10620.21L       C805H58                      C389
078.10521.08F1     C402-TO0D2H24                C390
078.10521.08F1     C402-TO0D2H24                C391
078.10521.08F1     C402-TO0D2H24                C392
078.10521.08F1     C402-TO0D2H24                C393
078.10521.08F1     C402-TO0D2H24                C394
078.10521.08F1     C402-TO0D2H24                C395
78.10420.50L       C0201H13                     C396
78.10420.50L       C0201H13                     C397
78.10420.50L       C0201H13                     C398
78.10420.50L       C0201H13                     C399
78.10420.50L       C0201H13                     C400
78.10420.50L       C0201H13                     C401
78.10420.50L       C0201H13                     C402
78.10420.50L       C0201H13                     C403
78.10420.50L       C0201H13                     C404
78.10420.50L       C0201H13                     C405
78.10420.50L       C0201H13                     C406
78.10420.50L       C0201H13                     C407
78.10420.50L       C0201H13                     C408
78.10420.50L       C0201H13                     C409
78.10420.50L       C0201H13                     C410
78.10420.50L       C0201H13                     C411
78.10420.50L       C0201H13                     C412
78.10420.50L       C0201H13                     C413
78.10420.50L       C0201H13                     C414
78.10420.50L       C0201H13                     C415
78.10420.50L       C0201H13                     C416
78.10420.50L       C0201H13                     C417
78.10420.50L       C0201H13                     C418
78.10420.50L       C0201H13                     C419
78.10420.50L       C0201H13                     C420
78.10420.50L       C0201H13                     C421
78.10420.50L       C0201H13                     C422
78.10224.2FL       C402H22                      C423
78.10224.2FL       C402H22                      C424
78.10224.2FL       C402H22                      C425
78.10224.2FL       C402H22                      C426
78.10224.2FL       C402H22                      C427
78.10224.2FL       C402H22                      C428
78.10224.2FL       C402H22                      C429
78.10224.2FL       C402H22                      C430
78.10421.2FL       C402H22                      C431
78.10421.2FL       C402H22                      C432
78.10421.2FL       C402H22                      C433
78.10421.2FL       C402H22                      C434
78.10421.2FL       C402H22                      C435
78.10421.2FL       C402H22                      C436
78.10421.2FL       C402H22                      C437
78.10421.2FL       C402H22                      C438
78.10421.2FL       C402H22                      C439
78.10421.2FL       C402H22                      C440
78.10421.2FL       C402H22                      C441
78.10421.2FL       C402H22                      C442
78.10421.2FL       C402H22                      C443
78.10421.2FL       C402H22                      C444
78.10421.2FL       C402H22                      C445
78.10421.2FL       C402H22                      C446
78.10421.2FL       C402H22                      C447
78.10421.2FL       C402H22                      C448
78.10421.2FL       C402H22                      C449
78.10421.2FL       C402H22                      C450
78.10421.2FL       C402H22                      C451
78.10421.2FL       C402H22                      C452
78.10421.2FL       C402H22                      C453
78.10421.2FL       C402H22                      C454
78.10421.2FL       C402H22                      C455
78.10421.2FL       C402H22                      C456
78.10421.2FL       C402H22                      C457
78.10421.2FL       C402H22                      C458
78.10421.2FL       C402H22                      C459
78.10421.2FL       C402H22                      C460
078.10521.08F1     C402-TO0D2H24                C461
078.10521.08F1     C402-TO0D2H24                C462
078.10521.08F1     C402-TO0D2H24                C463
078.10521.08F1     C402-TO0D2H24                C464
078.10521.08F1     C402-TO0D2H24                C465
078.10521.08F1     C402-TO0D2H24                C466
78.10421.2FL       C402H22                      C467
78.10421.2FL       C402H22                      C468
78.10421.2FL       C402H22                      C469
78.10421.2FL       C402H22                      C470
78.10421.2FL       C402H22                      C471
78.10421.2FL       C402H22                      C472
78.10224.2FL       C402H22                      C473
78.10224.2FL       C402H22                      C474
78.10224.2FL       C402H22                      C475
78.10224.2FL       C402H22                      C476
78.10224.2FL       C402H22                      C477
78.10224.2FL       C402H22                      C478
78.10224.2FL       C402H22                      C479
78.10224.2FL       C402H22                      C480
78.10421.2FL       C402H22                      C481
78.10421.2FL       C402H22                      C482
78.10421.2FL       C402H22                      C483
78.10421.2FL       C402H22                      C484
78.10421.2FL       C402H22                      C485
078.10321.02S1     C0201H13                     C486
078.10321.02S1     C0201H13                     C487
078.10321.02S1     C0201H13                     C488
078.10321.02S1     C0201H13                     C489
078.10321.02S1     C0201H13                     C490
078.10321.02S1     C0201H13                     C491
078.10321.02S1     C0201H13                     C492
078.10321.02S1     C0201H13                     C493
078.10321.02S1     C0201H13                     C494
078.10321.02S1     C0201H13                     C495
078.10321.02S1     C0201H13                     C496
078.10321.02S1     C0201H13                     C497
078.10321.02S1     C0201H13                     C498
078.10321.02S1     C0201H13                     C499
078.10321.02S1     C0201H13                     C500
078.10321.02S1     C0201H13                     C501
78.10421.2FL       C402H22                      C502
78.10421.2FL       C402H22                      C503
78.10421.2FL       C402H22                      C504
78.10421.2FL       C402H22                      C505
78.10421.2FL       C402H22                      C506
78.10421.2FL       C402H22                      C507
78.10421.2FL       C402H22                      C508
79.47719.2BL       CT7343H83                    C509
78.10421.2FL       C402H22                      C510
078.10621.0211     C805H58                      C511
078.10621.0211     C805H58                      C512
78.10421.2FL       C402H22                      C513
78.10421.2FL       C402H22                      C514
78.10421.2FL       C402H22                      C515
78.10421.2FL       C402H22                      C516
78.10421.2FL       C402H22                      C517
78.10422.2FL       C402H22                      C518
78.10422.2FL       C402H22                      C519
78.10422.2FL       C402H22                      C520
78.10421.2FL       C402H22                      C521
78.10422.2FL       C402H22                      C522
78.10421.2FL       C402H22                      C523
078.10521.08F1     C402-TO0D2H24                C524
078.1022S.022L     C1206H58                     C525
078.1022S.022L     C1206H58                     C526
078.1022S.022L     C1206H58                     C527
078.1022S.022L     C1206H58                     C528
078.1022S.022L     C1206H58                     C529
78.22224.2FL       C402H22                      C744
78.10521.2BL       C603H36                      C998
78.10421.2FL       C402H22                      C999
78.22522.21L       C805H54                      CA1
020.80818.0001     PREFIT-200P-360520-1H542     CN1
021.60653.0103     211-91-03GB01                CN5
83.SMF15.0AH       SOD123AK-2H43                D1
083.5V0X1.00AF     SOD523AKH26                  D2
083.5V0X1.00AF     SOD523AKH26                  D3
83.SMF15.0AH       SOD123AK-2H43                D4
83.SMF15.0AH       SOD123AK-2H43                D5
83.R2003.K8F       SOD323AKH42                  D11
75.005V0.A77       SOD882-10D6-1H20             D13
75.005V0.A77       SOD882-10D6-1H20             D14
75.005V0.A77       SOD882-10D6-1H20             D15
75.005V0.A77       SOD882-10D6-1H20             D16
75.005V0.A77       SOD882-10D6-1H20             D17
83.0005V.MAF       SOD882-10D6-1H20             D18
83.0005V.MAF       SOD882-10D6-1H20             D19
020.80074.0036     PREFIT-42P-131384H522        EXT1
020.80074.0036     PREFIT-42P-131384H522        EXT2
ZZ.C0N2C.011       GAP-CLOSE-PWR-4              G1
ZZ.CON2C.XXX       CON2C-U                      G2
ZZ.CON2C.XXX       CON2C-U                      G3
ZZ.C0N2C.011       GAP-CLOSE-PWR-4              G4
ZZ.CON2C.XXX       CON2C-U                      G5
68.00201.141       L2012-4P-1MH40               L1
68.00109.171       L805H42                      L2
68.00109.171       L805H42                      L3
68.00109.171       L805H42                      L4
68.00109.171       L805H42                      L5
68.00084.831       L20125H42                    L6
68.4R71A.20Q       L11102530H158                L7
68.00084.831       L20125H42                    L8
68.3R310.20V       L7066-1830-UH119             L9
068.3R310.2091     L4947-1215H119               L10
68.00084.771       L451616H71                   L11
68.R2410.20A       L7267-1630H158               L12
68.00224.201       L805H42                      L13
68.00224.201       L805H42                      L14
68.00224.201       L805H42                      L15
68.00224.201       L805H42                      L16
68.00224.201       L805H42                      L17
68.00224.201       L805H42                      L18
68.00224.201       L805H42                      L19
68.00224.051       L805H42                      L20
68.00395.001       L9546-152127H121             L21
68.00084.A61       L20125H42                    L23
06.WP130.14A       LED-100-3PH206               LED2
06.WP130.14A       LED-100-3PH206               LED3
83.01921.S70       LED1608AKH40                 LED4
83.01921.S70       LED1608AKH40                 LED5
83.01921.S70       LED1608AKH40                 LED6
06.WP130.14A       LED-100-3PH206               LED7
20.F1354.120       61082-121402LF-U1            MEZZ1
087.71242.0465     STF256R168H278               NUT1
082.20005.0001     OSC-3225-4P-3H48             OSC1
ZZ.00PAD.M21       0R0603-PAD-1-U               P1
84.03904.T11       SOT23CBE2D4H44               PQ1
84.2N702.031       SOT23DGS2D4H44               PQ2
84.08878.A37       SOIC8H69                     PQ3
84.2N702.031       SOT23DGS2D4H44               PQ4
84.08878.A37       SOIC8H69                     PQ5
ZZ.CON2C.XXX       CON2C-U                      PSP1
74.53318.073       DFN22G6050-G6133H60          PU1
74.53318.073       DFN22G6050-G6133H60          PU2
74.53312.073       QFN16G3-G1D7H40              PU4
74.74801.A33       QFN20-1G3D15H40              PU7
74.00235.033       QFN19-1H40                   PU8
74.74801.A33       QFN20-1G3D15H40              PU9
74.74801.A33       QFN20-1G3D15H40              PU10
74.74801.A33       QFN20-1G3D15H40              PU11
022.40001.0221     DTSA-65N-K-S-V-676-K         PWR1
84.03904.T11       SOT23CBE2D4H44               Q2
84.03904.T11       SOT23CBE2D4H44               Q3
84.2N702.031       SOT23DGS2D4H44               Q4
84.0R925.03N       LFPAK-5PH48-U                Q5
84.2N702.031       SOT23DGS2D4H44               Q6
84.2N702.031       SOT23DGS2D4H44               Q7
84.2N702.031       SOT23DGS2D4H44               Q8
084.3K324.0031     SOT23DGS2D4H35               Q9
84.2N702.031       SOT23DGS2D4H44               Q11
84.2N702.031       SOT23DGS2D4H44               Q12
084.3K324.0031     SOT23DGS2D4H35               Q14
084.3K324.0031     SOT23DGS2D4H35               Q15
84.2N702.031       SOT23DGS2D4H44               Q16
84.2N702.031       SOT23DGS2D4H44               Q17
84.2N702.031       SOT23DGS2D4H44               Q20
084.3K324.0031     SOT23DGS2D4H35               Q21
084.3K324.0031     SOT23DGS2D4H35               Q22
084.3K324.0031     SOT23DGS2D4H35               Q24
84.2N702.031       SOT23DGS2D4H44               Q25
84.2N702.031       SOT23DGS2D4H44               Q26
084.3K324.0031     SOT23DGS2D4H35               Q27
84.06P39.03F       UMT6H30                      Q28
84.2N702.031       SOT23DGS2D4H44               Q29
84.06P39.03F       UMT6H30                      Q205
84.06P39.03F       UMT6H30                      Q206
64.47015.6DL       R402H16                      R3
63.R0034.1DL       R402H16                      R4
63.R0034.1DL       R402H16                      R5
63.R0034.1DL       R402H16                      R7
63.R0034.1DL       R402H16                      R8
63.R0034.1DL       R402H16                      R9
63.R0034.1DL       R402H16                      R10
63.R0034.1DL       R402H16                      R14
63.R0034.1DL       R402H16                      R15
64.10025.6DL       R402H16                      R16
64.47015.6DL       R402H16                      R18
64.47015.6DL       R402H16                      R19
64.47015.6DL       R402H16                      R20
64.47015.6DL       R402H16                      R21
64.47015.6DL       R402H16                      R22
64.47015.6DL       R402H16                      R23
64.10025.6DL       R402H16                      R24
64.15025.6DL       R402H16                      R25
63.R0034.1DL       R402H16                      R26
64.10045.6DL       R402H16                      R27
63.12334.1DL       R402H16                      R28
64.47015.6DL       R402H16                      R29
64.47015.6DL       R402H16                      R30
64.47015.6DL       R402H16                      R31
64.47015.6DL       R402H16                      R32
64.47015.6DL       R402H16                      R33
64.47015.6DL       R402H16                      R34
64.47015.6DL       R402H16                      R35
64.47015.6DL       R402H16                      R36
64.10045.6DL       R402H16                      R37
63.R0034.1DL       R402H16                      R38
64.10045.6DL       R402H16                      R39
64.47015.6DL       R402H16                      R40
64.47015.6DL       R402H16                      R41
64.47015.6DL       R402H16                      R42
64.47015.6DL       R402H16                      R43
64.10045.6DL       R402H16                      R44
64.10045.6DL       R402H16                      R45
63.R0034.1DL       R402H16                      R46
64.10045.6DL       R402H16                      R47
64.47015.6DL       R402H16                      R48
64.10025.6DL       R402H16                      R49
64.47015.6DL       R402H16                      R50
64.33R05.6DL       R402H16                      R51
64.33R05.6DL       R402H16                      R52
64.47015.6DL       R402H16                      R53
63.R0034.1DL       R402H16                      R54
64.10025.6DL       R402H16                      R56
64.33R05.6DL       R402H16                      R58
64.33R05.6DL       R402H16                      R59
64.10025.6DL       R402H16                      R64
63.82234.1DL       R402H16                      R65
64.47515.6DL       R402H16                      R71
64.10025.6DL       R402H16                      R72
64.47515.6DL       R402H16                      R73
63.R0034.1DL       R402H16                      R74
63.R0034.1DL       R402H16                      R75
64.47025.6DL       R402H16                      R76
64.10025.6DL       R402H16                      R77
64.10025.6DL       R402H16                      R78
64.47035.6DL       R402H16                      R79
64.10035.6DL       R402H16                      R80
64.47515.6DL       R402H16                      R81
64.10025.6DL       R402H16                      R82
63.22234.1DL       R402H16                      R83
64.47015.6DL       R402H16                      R84
64.10035.6DL       R402H16                      R85
63.22234.1DL       R402H16                      R86
64.10035.6DL       R402H16                      R87
64.10035.6DL       R402H16                      R88
64.33R25.6DL       R402H16                      R89
63.22234.1DL       R402H16                      R90
64.30005.6DL       R402H16                      R91
63.R0034.1DL       R402H16                      R92
63.R0034.1DL       R402H16                      R93
63.R0034.1DL       R402H16                      R95
63.R0034.1DL       R402H16                      R96
63.R0034.1DL       R402H16                      R97
63.R0034.1DL       R402H16                      R98
63.R0034.1DL       R402H16                      R99
63.R0034.1DL       R402H16                      R100
63.R0034.1DL       R402H16                      R101
63.R0034.1DL       R402H16                      R102
64.47015.6DL       R402H16                      R105
63.R0034.1DL       R402H16                      R123
63.R0034.1DL       R402H16                      R124
63.R0034.1DL       R402H16                      R127
63.R0034.1DL       R402H16                      R128
63.R0034.1DL       R402H16                      R129
63.R0034.1DL       R402H16                      R130
63.R0034.1DL       R402H16                      R131
63.R0034.1DL       R402H16                      R132
63.82234.1DL       R402H16                      R133
63.82234.1DL       R402H16                      R134
63.82234.1DL       R402H16                      R135
63.82234.1DL       R402H16                      R136
63.82234.1DL       R402H16                      R137
63.82234.1DL       R402H16                      R138
63.82234.1DL       R402H16                      R139
64.10035.6DL       R402H16                      R140
64.10016.6DL       R402H16                      R141
64.20005.6DL       R402H16                      R142
64.10016.6DL       R402H16                      R143
64.47015.6DL       R402H16                      R144
64.24005.6DL       R402H16                      R145
64.10035.6DL       R402H16                      R146
64.10035.6DL       R402H16                      R147
64.10035.6DL       R402H16                      R148
64.10035.6DL       R402H16                      R149
63.R0034.1DL       R402H16                      R151
63.R0034.1DL       R402H16                      R152
63.R0034.1DL       R402H16                      R153
63.R0034.1DL       R402H16                      R154
63.R0034.1DL       R402H16                      R155
63.R0034.1DL       R402H16                      R156
63.R0034.1DL       R402H16                      R157
63.R0034.1DL       R402H16                      R158
63.R0034.1DL       R402H16                      R159
63.R0034.1DL       R402H16                      R160
63.R0034.1DL       R402H16                      R161
63.R0034.1DL       R402H16                      R162
63.R0034.1DL       R402H16                      R163
63.R0034.1DL       R402H16                      R164
63.R0034.1DL       R402H16                      R165
63.R0034.1DL       R402H16                      R166
63.R0034.1DL       R402H16                      R167
63.R0034.1DL       R402H16                      R168
63.R0034.1DL       R402H16                      R169
63.R0034.1DL       R402H16                      R170
63.R0034.1DL       R402H16                      R171
63.R0034.1DL       R402H16                      R172
63.R0034.1DL       R402H16                      R173
63.R0034.1DL       R402H16                      R174
63.R0034.1DL       R402H16                      R175
63.R0034.1DL       R402H16                      R176
63.R0034.1DL       R402H16                      R177
63.R0034.1DL       R402H16                      R178
64.22015.6DL       R402H16                      R179
64.22015.6DL       R402H16                      R180
64.22015.6DL       R402H16                      R181
64.22015.6DL       R402H16                      R182
64.22015.6DL       R402H16                      R183
64.22015.6DL       R402H16                      R184
64.22015.6DL       R402H16                      R185
64.22015.6DL       R402H16                      R186
64.22015.6DL       R402H16                      R187
64.22015.6DL       R402H16                      R188
64.49905.6DL       R402H16                      R189
64.49905.6DL       R402H16                      R190
64.22015.6DL       R402H16                      R191
64.22015.6DL       R402H16                      R192
64.20025.6DL       R402H16                      R193
64.20025.6DL       R402H16                      R194
64.22015.6DL       R402H16                      R195
64.22015.6DL       R402H16                      R196
64.22015.6DL       R402H16                      R197
64.10015.6DL       R402H16                      R198
64.10015.6DL       R402H16                      R199
64.22015.6DL       R402H16                      R200
64.22015.6DL       R402H16                      R201
64.22015.6DL       R402H16                      R202
64.22015.6DL       R402H16                      R203
64.22015.6DL       R402H16                      R204
64.60R45.6DL       R402H16                      R205
64.60R45.6DL       R402H16                      R206
64.12005.6DL       R402H16                      R207
64.12005.6DL       R402H16                      R208
64.12005.6DL       R402H16                      R209
64.12005.6DL       R402H16                      R210
64.12005.6DL       R402H16                      R211
64.12005.6DL       R402H16                      R212
64.12005.6DL       R402H16                      R213
64.27015.6DL       R402H16                      R214
64.12005.6DL       R402H16                      R215
64.12005.6DL       R402H16                      R216
64.12005.6DL       R402H16                      R217
64.12005.6DL       R402H16                      R218
64.24005.6DL       R402H16                      R219
64.12005.6DL       R402H16                      R220
64.12005.6DL       R402H16                      R221
64.12005.6DL       R402H16                      R222
64.12005.6DL       R402H16                      R223
64.47015.6DL       R402H16                      R224
64.12005.6DL       R402H16                      R225
64.12005.6DL       R402H16                      R226
64.12005.6DL       R402H16                      R227
64.12005.6DL       R402H16                      R228
64.12005.6DL       R402H16                      R229
64.12005.6DL       R402H16                      R230
64.12005.6DL       R402H16                      R231
64.12005.6DL       R402H16                      R232
64.12005.6DL       R402H16                      R233
64.12005.6DL       R402H16                      R234
64.12005.6DL       R402H16                      R235
64.12005.6DL       R402H16                      R236
64.12005.6DL       R402H16                      R237
64.12005.6DL       R402H16                      R238
63.R0034.1DL       R402H16                      R239
64.12005.6DL       R402H16                      R240
64.12005.6DL       R402H16                      R241
64.12005.6DL       R402H16                      R242
64.12005.6DL       R402H16                      R243
64.12005.6DL       R402H16                      R244
64.12005.6DL       R402H16                      R245
64.12005.6DL       R402H16                      R246
64.12005.6DL       R402H16                      R247
64.12005.6DL       R402H16                      R248
64.12005.6DL       R402H16                      R249
64.12005.6DL       R402H16                      R250
64.12005.6DL       R402H16                      R251
64.12005.6DL       R402H16                      R252
64.12005.6DL       R402H16                      R253
64.12005.6DL       R402H16                      R254
64.12005.6DL       R402H16                      R255
64.12005.6DL       R402H16                      R256
64.12005.6DL       R402H16                      R257
64.12005.6DL       R402H16                      R258
64.12005.6DL       R402H16                      R259
64.12005.6DL       R402H16                      R260
64.12005.6DL       R402H16                      R261
64.47015.6DL       R402H16                      R262
64.47015.6DL       R402H16                      R263
64.47015.6DL       R402H16                      R264
64.47015.6DL       R402H16                      R265
63.22234.1DL       R402H16                      R266
63.22234.1DL       R402H16                      R267
63.22234.1DL       R402H16                      R268
63.22234.1DL       R402H16                      R269
64.33R05.6DL       R402H16                      R270
64.47015.6DL       R402H16                      R271
64.47015.6DL       R402H16                      R272
64.47015.6DL       R402H16                      R273
64.10035.6DL       R402H16                      R275
64.47015.6DL       R402H16                      R276
64.33R05.6DL       R402H16                      R277
63.R0034.1DL       R402H16                      R278
63.R0034.1DL       R402H16                      R279
64.33R05.6DL       R402H16                      R280
63.R0034.1DL       R402H16                      R281
64.47015.6DL       R402H16                      R282
64.33R05.6DL       R402H16                      R283
64.33R05.6DL       R402H16                      R284
64.47015.6DL       R402H16                      R285
63.R0034.1DL       R402H16                      R286
63.R0034.1DL       R402H16                      R287
63.R0034.1DL       R402H16                      R288
63.R0034.1DL       R402H16                      R289
63.R0034.1DL       R402H16                      R290
63.R0034.1DL       R402H16                      R291
63.R0034.1DL       R402H16                      R292
63.R0034.1DL       R402H16                      R293
63.R0034.1DL       R402H16                      R294
63.R0034.1DL       R402H16                      R295
63.R0034.1DL       R402H16                      R297
63.R0034.1DL       R402H16                      R298
64.47015.6DL       R402H16                      R299
64.47015.6DL       R402H16                      R300
63.R0034.1DL       R402H16                      R301
63.R0034.1DL       R402H16                      R302
64.47025.6DL       R402H16                      R303
64.47025.6DL       R402H16                      R304
64.10025.6DL       R402H16                      R305
63.33034.1DL       R402H16                      R306
64.10025.6DL       R402H16                      R307
64.47015.6DL       R402H16                      R308
64.47015.6DL       R402H16                      R309
64.47015.6DL       R402H16                      R310
64.47015.6DL       R402H16                      R311
63.R0034.1DL       R402H16                      R312
64.47015.6DL       R402H16                      R313
63.R0034.1DL       R402H16                      R314
64.10025.6DL       R402H16                      R315
63.R0034.1DL       R402H16                      R316
63.R0034.1DL       R402H16                      R317
63.R0034.1DL       R402H16                      R318
63.R0034.1DL       R402H16                      R319
63.R0034.1DL       R402H16                      R320
63.R0034.1DL       R402H16                      R321
63.R0034.1DL       R402H16                      R322
64.47015.6DL       R402H16                      R323
64.47015.6DL       R402H16                      R324
63.R0034.1DL       R402H16                      R325
63.R0034.1DL       R402H16                      R326
64.47015.6DL       R402H16                      R327
63.R0034.1DL       R402H16                      R328
63.R0034.1DL       R402H16                      R329
64.47015.6DL       R402H16                      R330
64.47015.6DL       R402H16                      R331
64.47015.6DL       R402H16                      R332
63.R0034.1DL       R402H16                      R333
63.R0034.1DL       R402H16                      R334
63.R0034.1DL       R402H16                      R335
64.47015.6DL       R402H16                      R336
64.47015.6DL       R402H16                      R337
63.82234.1DL       R402H16                      R338
64.47015.6DL       R402H16                      R339
63.82234.1DL       R402H16                      R340
64.47015.6DL       R402H16                      R341
63.R0034.1DL       R402H16                      R342
63.R0034.1DL       R402H16                      R343
63.R0034.1DL       R402H16                      R344
63.R0034.1DL       R402H16                      R345
64.15005.6DL       R402H16                      R346
64.47015.6DL       R402H16                      R347
63.R0034.1DL       R402H16                      R348
63.R0034.1DL       R402H16                      R349
63.R0034.1DL       R402H16                      R350
64.10025.6DL       R402H16                      R351
64.47015.6DL       R402H16                      R352
64.47015.6DL       R402H16                      R353
64.47015.6DL       R402H16                      R354
64.47015.6DL       R402H16                      R355
63.R0034.1DL       R402H16                      R356
64.47015.6DL       R402H16                      R357
64.10025.6DL       R402H16                      R358
64.10025.6DL       R402H16                      R359
64.10025.6DL       R402H16                      R360
64.10025.6DL       R402H16                      R361
64.47015.6DL       R402H16                      R362
64.47015.6DL       R402H16                      R363
64.47015.6DL       R402H16                      R364
64.47015.6DL       R402H16                      R365
64.49925.6DL       R402H16                      R366
064.18025.06DL     R402H16                      R367
63.R0034.1DL       R402H16                      R368
64.47015.6DL       R402H16                      R369
64.47015.6DL       R402H16                      R370
64.47015.6DL       R402H16                      R371
64.47015.6DL       R402H16                      R372
64.47015.6DL       R402H16                      R373
64.47015.6DL       R402H16                      R374
64.47015.6DL       R402H16                      R375
64.47015.6DL       R402H16                      R376
64.47015.6DL       R402H16                      R377
64.47015.6DL       R402H16                      R378
64.47015.6DL       R402H16                      R379
64.47015.6DL       R402H16                      R380
64.47015.6DL       R402H16                      R381
64.47015.6DL       R402H16                      R382
64.47015.6DL       R402H16                      R383
64.47015.6DL       R402H16                      R384
64.47015.6DL       R402H16                      R385
64.47015.6DL       R402H16                      R386
64.47015.6DL       R402H16                      R387
64.47015.6DL       R402H16                      R388
64.47015.6DL       R402H16                      R389
64.47015.6DL       R402H16                      R390
64.47015.6DL       R402H16                      R391
64.47015.6DL       R402H16                      R392
64.47015.6DL       R402H16                      R393
64.47015.6DL       R402H16                      R394
64.47015.6DL       R402H16                      R395
64.47015.6DL       R402H16                      R396
64.47015.6DL       R402H16                      R397
64.47015.6DL       R402H16                      R398
64.47015.6DL       R402H16                      R399
64.47015.6DL       R402H16                      R400
64.78715.6DL       R402H16                      R401
64.33005.6DL       R402H16                      R402
64.33005.6DL       R402H16                      R403
64.10015.6DL       R402H16                      R404
64.10015.6DL       R402H16                      R405
64.10015.6DL       R402H16                      R406
64.14015.6DL       R402H16                      R407
64.10015.6DL       R402H16                      R408
64.14015.6DL       R402H16                      R409
64.10015.6DL       R402H16                      R410
64.10015.6DL       R402H16                      R411
64.10015.6DL       R402H16                      R412
64.27015.6DL       R402H16                      R413
64.10015.6DL       R402H16                      R414
64.10015.6DL       R402H16                      R415
64.10015.6DL       R402H16                      R416
63.R0034.1DL       R402H16                      R417
63.R0034.1DL       R402H16                      R418
63.R0034.1DL       R402H16                      R419
64.47015.6DL       R402H16                      R420
64.10025.6DL       R402H16                      R421
64.47015.6DL       R402H16                      R422
64.47015.6DL       R402H16                      R423
64.47015.6DL       R402H16                      R424
64.47015.6DL       R402H16                      R425
63.R0034.1DL       R402H16                      R426
63.R0034.1DL       R402H16                      R427
64.47015.6DL       R402H16                      R428
64.47015.6DL       R402H16                      R429
64.47015.6DL       R402H16                      R430
64.10R05.6DL       R402H14                      R431
64.10006.6DL       R402H14                      R432
64.10025.6DL       R402H16                      R433
64.10006.6DL       R402H14                      R434
64.38315.6DL       R402H16                      R435
63.R0034.1DL       R402H16                      R436
64.10035.6DL       R402H16                      R437
63.10334.1DL       R402H16                      R438
64.11025.6DL       R402H16                      R439
64.10R05.6DL       R402H14                      R440
64.10R05.6DL       R402H14                      R441
64.10R05.6DL       R402H14                      R442
64.10R05.6DL       R402H14                      R443
64.R0025.L1L       RL3115-4PH45                 R444
64.49925.6DL       R402H16                      R445
64.49925.6DL       R402H16                      R446
064.41215.06DS     R402H16                      R447
064.51015.06DS     R402H16                      R448
63.10234.1DL       R402H16                      R449
64.10R05.16L       R805H24                      R450
64.10025.6DL       R402H16                      R451
63.R0034.1DL       R402H16                      R452
63.10434.L1L       R402H15                      R453
64.51025.6DL       R402H16                      R454
63.10533.15L       R603H22                      R455
63.R0034.1DL       R402H16                      R456
63.10434.L1L       R402H15                      R457
64.86625.6DL       R402H16                      R458
63.R0034.1DL       R402H16                      R459
63.R0034.1DL       R402H16                      R460
63.10434.L1L       R402H15                      R461
64.22625.6DL       R402H16                      R462
64.10025.6DL       R402H16                      R463
64.2R205.55L       R603H22                      R464
64.22015.6DL       R402H16                      R465
63.2R734.15L       R603H22                      R466
64.10025.6DL       R402H16                      R467
63.33234.1DL       R402H16                      R468
64.3R015.16L       R805H24                      R469
64.20035.6DL       R402H16                      R470
64.15025.6DL       R402H16                      R471
64.10035.6DL       R402H16                      R472
64.10R05.55L       R603H22                      R473
64.73225.6DL       R402H16                      R474
64.57626.6DL       R402H16                      R475
64.86635.6DL       R402H16                      R476
64.61935.6DL       R402H16                      R477
64.10025.6DL       R402H16                      R478
63.R0032.11L       R1206H28                     R479
63.R0032.11L       R1206H28                     R480
63.R0032.11L       R1206H28                     R481
63.10334.1DL       R402H16                      R482
63.2R233.15L       R603H22                      R483
64.3R015.16L       R805H24                      R484
63.R0034.1DL       R402H16                      R485
64.38315.6DL       R402H16                      R486
64.10025.6DL       R402H16                      R487
64.27015.6DL       R402H16                      R488
64.10R05.55L       R603H22                      R489
64.3R015.16L       R805H24                      R490
64.15025.6DL       R402H16                      R491
64.47535.6DL       R402H16                      R492
64.10035.6DL       R402H16                      R493
64.57626.6DL       R402H16                      R494
64.86635.6DL       R402H16                      R495
64.44225.6DL       R402H16                      R496
64.61935.6DL       R402H16                      R497
63.R0034.1DL       R402H16                      R498
64.10025.6DL       R402H16                      R499
63.22234.1DL       R402H16                      R500
63.22234.1DL       R402H16                      R501
64.10045.6DL       R402H16                      R502
64.10015.6DL       R402H16                      R503
63.R0031.16L       R805H24                      R504
64.35715.6DL       R402H16                      R505
64.16915.6DL       R402H16                      R506
64.10025.6DL       R402H16                      R507
63.R0034.1DL       R402H16                      R508
64.47515.6DL       R402H16                      R509
63.R0034.1DL       R402H16                      R510
64.2R205.55L       R603H22                      R511
63.R0032.11L       R1206H28                     R512
64.10025.6DL       R402H16                      R513
64.10R05.55L       R603H22                      R514
64.13725.6DL       R402H16                      R515
63.R0034.1DL       R402H16                      R516
63.R0034.1DL       R402H16                      R517
64.10025.6DL       R402H16                      R518
64.10015.6DL       R402H16                      R519
64.3R015.16L       R805H24                      R520
64.15025.6DL       R402H16                      R521
63.R0034.1DL       R402H16                      R522
64.45315.6DL       R402H16                      R523
64.47015.6DL       R402H16                      R524
64.10025.6DL       R402H16                      R525
64.47015.6DL       R402H16                      R526
64.47015.6DL       R402H16                      R527
64.10015.6DL       R402H16                      R528
63.R0031.16L       R805H24                      R529
64.24915.6DL       R402H16                      R530
64.49915.6DL       R402H16                      R531
64.10025.6DL       R402H16                      R532
63.R0034.1DL       R402H16                      R533
64.47515.6DL       R402H16                      R534
63.R0034.1DL       R402H16                      R535
63.R0031.16L       R805H24                      R536
29L2161AA          R402H16                      R537
64.46415.6DL       R402H16                      R538
64.10025.6DL       R402H16                      R539
63.R0034.1DL       R402H16                      R540
64.47515.6DL       R402H16                      R541
63.R0034.1DL       R402H16                      R542
63.R0031.16L       R805H24                      R543
64.42215.6DL       R402H16                      R544
64.47515.6DL       R402H16                      R545
64.10025.6DL       R402H16                      R546
63.R0034.1DL       R402H16                      R547
64.47515.6DL       R402H16                      R548
63.R0034.1DL       R402H16                      R549
64.47015.6DL       R402H16                      R550
64.47015.6DL       R402H16                      R551
64.47015.6DL       R402H16                      R552
64.10025.6DL       R402H16                      R553
64.19125.6DL       R402H16                      R554
64.22105.6DL       R402H16                      R555
64.10025.6DL       R402H16                      R556
64.12115.6DL       R402H16                      R557
63.R0034.1DL       R402H16                      R558
64.10025.6DL       R402H16                      R559
64.69825.6DL       R402H16                      R560
64.10025.6DL       R402H16                      R561
64.10035.6DL       R402H16                      R562
64.10035.6DL       R402H16                      R563
64.73215.6DL       R402H16                      R564
64.22105.6DL       R402H16                      R565
64.45305.6DL       R402H16                      R566
64.47015.6DL       R402H16                      R567
64.10025.6DL       R402H16                      R568
64.51R05.6DL       R402H16                      R569
64.51R05.6DL       R402H16                      R570
63.R0034.1DL       R402H16                      R571
64.10025.6DL       R402H16                      R572
64.10025.6DL       R402H16                      R573
64.10025.6DL       R402H16                      R574
64.10025.6DL       R402H16                      R575
64.22015.6DL       R402H16                      R576
64.22015.6DL       R402H16                      R577
64.22015.6DL       R402H16                      R578
64.22015.6DL       R402H16                      R579
64.22015.6DL       R402H16                      R580
64.22015.6DL       R402H16                      R581
64.22015.6DL       R402H16                      R582
64.22015.6DL       R402H16                      R583
64.22015.6DL       R402H16                      R584
64.22015.6DL       R402H16                      R585
64.22015.6DL       R402H16                      R586
64.22015.6DL       R402H16                      R587
64.22015.6DL       R402H16                      R588
64.22015.6DL       R402H16                      R589
64.22015.6DL       R402H16                      R590
64.22015.6DL       R402H16                      R591
64.22015.6DL       R402H16                      R592
64.22015.6DL       R402H16                      R593
64.22015.6DL       R402H16                      R594
64.22015.6DL       R402H16                      R595
64.47015.6DL       R402H16                      R596
63.R0034.1DL       R402H16                      R597
64.10025.6DL       R402H16                      R598
64.47015.6DL       R402H16                      R599
64.47015.6DL       R402H16                      R600
64.47015.6DL       R402H16                      R601
63.R0034.1DL       R402H16                      R602
64.47015.6DL       R402H16                      R603
64.47015.6DL       R402H16                      R604
64.47015.6DL       R402H16                      R605
63.R0034.1DL       R402H16                      R606
63.R0034.1DL       R402H16                      R607
63.R0034.1DL       R402H16                      R608
63.R0034.1DL       R402H16                      R609
64.10035.6DL       R402H16                      R610
64.47015.6DL       R402H16                      R611
64.47015.6DL       R402H16                      R612
63.R0034.1DL       R402H16                      R613
63.R0034.1DL       R402H16                      R614
63.R0034.1DL       R402H16                      R615
64.47015.6DL       R402H16                      R616
63.R0034.1DL       R402H16                      R617
64.10025.6DL       R402H16                      R618
64.47015.6DL       R402H16                      R619
64.47015.6DL       R402H16                      R620
64.47015.6DL       R402H16                      R621
64.15005.6DL       R402H16                      R622
64.15005.6DL       R402H16                      R623
64.10025.6DL       R402H16                      R624
63.30234.1DL       R402H16                      R625
64.10025.6DL       R402H16                      R626
64.47015.6DL       R402H16                      R627
64.47015.6DL       R402H16                      R628
64.47015.6DL       R402H16                      R629
64.47015.6DL       R402H16                      R630
64.47015.6DL       R402H16                      R631
64.47015.6DL       R402H16                      R632
64.47015.6DL       R402H16                      R633
64.47015.6DL       R402H16                      R634
64.47015.6DL       R402H16                      R635
64.47015.6DL       R402H16                      R636
64.47015.6DL       R402H16                      R637
64.47015.6DL       R402H16                      R638
64.47015.6DL       R402H16                      R639
64.47015.6DL       R402H16                      R640
64.47015.6DL       R402H16                      R641
64.47015.6DL       R402H16                      R642
64.47015.6DL       R402H16                      R643
64.47015.6DL       R402H16                      R644
64.10025.6DL       R402H16                      R645
64.10025.6DL       R402H16                      R646
64.10025.6DL       R402H16                      R647
64.10025.6DL       R402H16                      R648
64.10025.6DL       R402H16                      R649
64.10025.6DL       R402H16                      R650
63.R0034.1DL       R402H16                      R651
64.10025.6DL       R402H16                      R652
64.10025.6DL       R402H16                      R653
64.10025.6DL       R402H16                      R654
64.10025.6DL       R402H16                      R655
64.10025.6DL       R402H16                      R656
64.10025.6DL       R402H16                      R657
64.47015.6DL       R402H16                      R658
64.47015.6DL       R402H16                      R659
64.10025.6DL       R402H16                      R660
64.10025.6DL       R402H16                      R661
64.10025.6DL       R402H16                      R662
64.10025.6DL       R402H16                      R663
64.10025.6DL       R402H16                      R664
64.10025.6DL       R402H16                      R665
64.10025.6DL       R402H16                      R666
64.10025.6DL       R402H16                      R667
64.10025.6DL       R402H16                      R668
64.10025.6DL       R402H16                      R669
64.10025.6DL       R402H16                      R670
64.10025.6DL       R402H16                      R671
64.10025.6DL       R402H16                      R672
64.10025.6DL       R402H16                      R673
64.10025.6DL       R402H16                      R674
64.10025.6DL       R402H16                      R675
64.10025.6DL       R402H16                      R676
64.10025.6DL       R402H16                      R677
64.10025.6DL       R402H16                      R678
64.10R05.6DL       R402H14                      R679
64.10R05.6DL       R402H14                      R680
64.10R05.6DL       R402H14                      R681
64.10R05.6DL       R402H14                      R682
64.10R05.6DL       R402H14                      R683
64.10R05.6DL       R402H14                      R684
64.10R05.6DL       R402H14                      R685
64.R5105.55L       R603H22                      R686
64.R5105.55L       R603H22                      R687
64.10035.6DL       R402H16                      R688
64.22015.6DL       R402H16                      R689
64.22015.6DL       R402H16                      R690
63.R0034.1DL       R402H16                      R691
63.R0034.1DL       R402H16                      R692
63.R0034.1DL       R402H16                      R693
63.R0034.1DL       R402H16                      R694
64.10015.6DL       R402H16                      R695
64.10015.6DL       R402H16                      R696
64.47015.6DL       R402H16                      R697
64.47015.6DL       R402H16                      R698
64.47015.6DL       R402H16                      R699
64.47015.6DL       R402H16                      R700
64.47015.6DL       R402H16                      R701
64.47015.6DL       R402H16                      R702
64.47015.6DL       R402H16                      R703
63.10434.L1L       R402H15                      R704
64.47015.6DL       R402H16                      R705
64.47015.6DL       R402H16                      R706
64.47015.6DL       R402H16                      R707
64.10025.6DL       R402H16                      R708
63.R0031.16L       R805H24                      R709
63.R0031.16L       R805H24                      R710
63.R0034.1DL       R402H16                      R711
63.R0034.1DL       R402H16                      R712
63.R0034.1DL       R402H16                      R713
63.R0034.1DL       R402H16                      R714
63.R0034.1DL       R402H16                      R715
64.10025.6DL       R402H16                      R716
63.R0034.1DL       R402H16                      R717
63.R0034.1DL       R402H16                      R718
63.R0034.1DL       R402H16                      R719
63.R0034.1DL       R402H16                      R720
64.47015.6DL       R402H16                      R721
63.10334.1DL       R402H16                      R722
64.47015.6DL       R402H16                      R723
63.R0034.1DL       R402H16                      R724
64.47015.6DL       R402H16                      R725
64.47015.6DL       R402H16                      R726
63.R0034.1DL       R402H16                      R727
64.47015.6DL       R402H16                      R728
64.10025.6DL       R402H16                      R729
64.10015.6DL       R402H16                      R730
63.R0034.1DL       R402H16                      R731
63.R0034.1DL       R402H16                      R732
64.12005.55L       R603H22                      R733
63.R0034.1DL       R402H16                      R734
64.10015.6DL       R402H16                      R735
63.R0034.1DL       R402H16                      R736
64.12005.55L       R603H22                      R737
64.47015.6DL       R402H16                      R738
64.10025.6DL       R402H16                      R739
64.47015.6DL       R402H16                      R740
63.R0034.1DL       R402H16                      R741
64.10025.6DL       R402H16                      R742
64.10035.6DL       R402H16                      R743
64.11025.6DL       R402H16                      R744
64.12005.55L       R603H22                      R745
64.10015.6DL       R402H16                      R746
64.10025.6DL       R402H16                      R747
64.10025.6DL       R402H16                      R748
63.33034.1DL       R402H16                      R763
63.R0034.1DL       R402H16                      R764
63.R0034.1DL       R402H16                      R765
64.10025.6DL       R402H16                      R766
64.10025.6DL       R402H16                      R767
63.R0034.1DL       R402H16                      R768
63.R0034.1DL       R402H16                      R769
63.R0034.1DL       R402H16                      R770
63.R0034.1DL       R402H16                      R771
63.R0034.1DL       R402H16                      R772
63.R0034.1DL       R402H16                      R773
64.10015.6DL       R402H16                      R774
64.10015.6DL       R402H16                      R775
64.10015.6DL       R402H16                      R776
64.10015.6DL       R402H16                      R777
64.86605.6DL       R402H16                      R778
64.10015.6DL       R402H16                      R779
63.33034.1DL       R402H16                      R780
63.R0034.1DL       R402H16                      R781
64.47015.6DL       R402H16                      R782
64.10025.6DL       R402H16                      R783
64.10025.6DL       R402H16                      R784
64.10025.6DL       R402H16                      R785
63.R0034.1DL       R402H16                      R786
63.R0034.1DL       R402H16                      R787
63.R0034.1DL       R402H16                      R788
63.R0034.1DL       R402H16                      R789
63.R0034.1DL       R402H16                      R795
63.R0034.1DL       R402H16                      R796
63.R0034.1DL       R402H16                      R797
64.13005.55L       R603H22                      R800
64.13005.55L       R603H22                      R801
64.13005.55L       R603H22                      R817
64.20035.6DL       R402H16                      R833
64.2R205.16L       R805H24                      R7909
022.40001.0681     DIPTRONICS                   RST1
62.10089.021       SKT-SOIC16-153139H258        SKT1
62.10089.021       SKT-SOIC16-153139H258        SKT2
082.30005.0311     SMD-OSC38H20                 SX1
ZZ.PAD28.XXX       TPAD28                       TP1
ZZ.PAD28.XXX       TPAD28                       TP2
ZZ.PAD28.XXX       TPAD28                       TP3
ZZ.PAD28.XXX       TPAD28                       TP4
ZZ.PAD28.XXX       TPAD28                       TP5
ZZ.PAD28.XXX       TPAD28                       TP6
ZZ.PAD28.XXX       TPAD28                       TP9
ZZ.PAD28.XXX       TPAD28                       TP10
ZZ.PAD28.XXX       TPAD28                       TP11
ZZ.PAD28.XXX       TPAD28                       TP12
ZZ.PAD28.XXX       TPAD28                       TP13
ZZ.PAD28.XXX       TPAD28                       TP14
ZZ.PAD28.XXX       TPAD28                       TP15
ZZ.PAD28.XXX       TPAD28                       TP16
ZZ.PAD28.XXX       TPAD28                       TP17
ZZ.PAD28.XXX       TPAD28                       TP18
ZZ.0TPAD.191       TPAD32                       TP19
ZZ.PAD28.XXX       TPAD28                       TP20
ZZ.PAD28.XXX       TPAD28                       TP21
ZZ.PAD28.XXX       TPAD28                       TP27
ZZ.PAD28.XXX       TPAD28                       TP28
ZZ.PAD28.XXX       TPAD28                       TP29
ZZ.PAD28.XXX       TPAD28                       TP50
ZZ.PAD28.XXX       TPAD28                       TP51
ZZ.PAD28.XXX       TPAD28                       TP52
ZZ.PAD28.XXX       TPAD28                       TP53
ZZ.PAD28.XXX       TPAD28                       TP54
ZZ.PAD28.XXX       TPAD28                       TP55
ZZ.PAD28.XXX       TPAD28                       TP57
ZZ.PAD28.XXX       TPAD28                       TP62
ZZ.PAD28.XXX       TPAD28                       TP63
ZZ.PAD28.XXX       TPAD28                       TP64
ZZ.PAD28.XXX       TPAD28                       TP65
ZZ.PAD28.XXX       TPAD28                       TP66
ZZ.PAD28.XXX       TPAD28                       TP68
ZZ.PAD28.XXX       TPAD28                       TP69
ZZ.PAD28.XXX       TPAD28                       TP70
ZZ.PAD28.XXX       TPAD28                       TP71
ZZ.PAD28.XXX       TPAD28                       TP72
ZZ.PAD28.XXX       TPAD28                       TP73
ZZ.PAD28.XXX       TPAD28                       TP74
ZZ.PAD28.XXX       TPAD28                       TP75
ZZ.PAD28.XXX       TPAD28                       TP76
ZZ.PAD28.XXX       TPAD28                       TP77
ZZ.PAD28.XXX       TPAD28                       TP78
ZZ.PAD28.XXX       TPAD28                       TP79
ZZ.PAD28.XXX       TPAD28                       TP80
ZZ.PAD28.XXX       TPAD28                       TP81
ZZ.PAD28.XXX       TPAD28                       TP82
ZZ.PAD28.XXX       TPAD28                       TP83
ZZ.PAD28.XXX       TPAD28                       TP84
ZZ.PAD28.XXX       TPAD28                       TP85
ZZ.PAD28.XXX       TPAD28                       TP86
ZZ.PAD28.XXX       TPAD28                       TP87
ZZ.PAD28.XXX       TPAD28                       TP88
ZZ.PAD28.XXX       TPAD28                       TP89
ZZ.PAD28.XXX       TPAD28                       TP90
ZZ.PAD28.XXX       TPAD28                       TP91
ZZ.PAD28.XXX       TPAD28                       TP92
ZZ.PAD28.XXX       TPAD28                       TP93
ZZ.PAD28.XXX       TPAD28                       TP94
ZZ.PAD28.XXX       TPAD28                       TP95
ZZ.PAD28.XXX       TPAD28                       TP96
ZZ.PAD28.XXX       TPAD28                       TP97
ZZ.PAD28.XXX       TPAD28                       TP98
ZZ.PAD28.XXX       TPAD28                       TP99
ZZ.PAD28.XXX       TPAD28                       TP100
ZZ.PAD28.XXX       TPAD28                       TP101
ZZ.PAD28.XXX       TPAD28                       TP102
ZZ.PAD28.XXX       TPAD28                       TP103
ZZ.PAD28.XXX       TPAD28                       TP104
ZZ.PAD28.XXX       TPAD28                       TP105
ZZ.PAD28.XXX       TPAD28                       TP106
ZZ.PAD28.XXX       TPAD28                       TP107
ZZ.PAD28.XXX       TPAD28                       TP108
ZZ.PAD28.XXX       TPAD28                       TP109
ZZ.PAD28.XXX       TPAD28                       TP110
ZZ.PAD28.XXX       TPAD28                       TP111
ZZ.PAD28.XXX       TPAD28                       TP112
ZZ.PAD28.XXX       TPAD28                       TP113
ZZ.PAD28.XXX       TPAD28                       TP114
ZZ.PAD28.XXX       TPAD28                       TP115
ZZ.PAD28.XXX       TPAD28                       TP116
ZZ.PAD28.XXX       TPAD28                       TP117
ZZ.PAD28.XXX       TPAD28                       TP118
ZZ.PAD28.XXX       TPAD28                       TP119
ZZ.PAD28.XXX       TPAD28                       TP120
ZZ.PAD28.XXX       TPAD28                       TP121
ZZ.PAD28.XXX       TPAD28                       TP122
ZZ.PAD28.XXX       TPAD28                       TP123
ZZ.PAD28.XXX       TPAD28                       TP124
ZZ.PAD28.XXX       TPAD28                       TP125
ZZ.PAD28.XXX       TPAD28                       TP126
ZZ.PAD28.XXX       TPAD28                       TP127
ZZ.PAD28.XXX       TPAD28                       TP128
ZZ.PAD28.XXX       TPAD28                       TP129
ZZ.PAD28.XXX       TPAD28                       TP130
ZZ.PAD28.XXX       TPAD28                       TP131
ZZ.PAD28.XXX       TPAD28                       TP133
ZZ.PAD28.XXX       TPAD28                       TP134
ZZ.PAD28.XXX       TPAD28                       TP135
ZZ.PAD28.XXX       TPAD28                       TP136
ZZ.PAD28.XXX       TPAD28                       TP137
ZZ.PAD28.XXX       TPAD28                       TP138
ZZ.PAD28.XXX       TPAD28                       TP139
ZZ.PAD28.XXX       TPAD28                       TP140
ZZ.PAD28.XXX       TPAD28                       TP141
ZZ.PAD28.XXX       TPAD28                       TP142
ZZ.PAD28.XXX       TPAD28                       TP143
ZZ.PAD28.XXX       TPAD28                       TP144
ZZ.PAD28.XXX       TPAD28                       TP145
ZZ.PAD28.XXX       TPAD28                       TP146
ZZ.PAD28.XXX       TPAD28                       TP147
ZZ.PAD28.XXX       TPAD28                       TP148
ZZ.PAD28.XXX       TPAD28                       TP149
ZZ.PAD28.XXX       TPAD28                       TP150
ZZ.PAD28.XXX       TPAD28                       TP151
ZZ.PAD28.XXX       TPAD28                       TP152
ZZ.PAD28.XXX       TPAD28                       TP153
ZZ.PAD28.XXX       TPAD28                       TP154
ZZ.PAD28.XXX       TPAD28                       TP155
ZZ.PAD28.XXX       TPAD28                       TP156
ZZ.PAD28.XXX       TPAD28                       TP157
ZZ.PAD28.XXX       TPAD28                       TP158
ZZ.PAD28.XXX       TPAD28                       TP159
ZZ.PAD28.XXX       TPAD28                       TP160
ZZ.PAD28.XXX       TPAD28                       TP161
ZZ.PAD28.XXX       TPAD28                       TP162
ZZ.PAD28.XXX       TPAD28                       TP163
ZZ.PAD28.XXX       TPAD28                       TP164
ZZ.PAD28.XXX       TPAD28                       TP165
ZZ.PAD28.XXX       TPAD28                       TP166
ZZ.PAD28.XXX       TPAD28                       TP167
ZZ.PAD28.XXX       TPAD28                       TP168
ZZ.PAD28.XXX       TPAD28                       TP169
ZZ.PAD28.XXX       TPAD28                       TP170
ZZ.PAD28.XXX       TPAD28                       TP171
ZZ.PAD28.XXX       TPAD28                       TP172
ZZ.PAD28.XXX       TPAD28                       TP173
ZZ.PAD28.XXX       TPAD28                       TP174
ZZ.PAD28.XXX       TPAD28                       TP175
ZZ.PAD28.XXX       TPAD28                       TP176
ZZ.PAD28.XXX       TPAD28                       TP177
ZZ.PAD28.XXX       TPAD28                       TP178
ZZ.PAD28.XXX       TPAD28                       TP179
ZZ.PAD28.XXX       TPAD28                       TP180
ZZ.PAD28.XXX       TPAD28                       TP181
ZZ.PAD28.XXX       TPAD28                       TP182
ZZ.PAD28.XXX       TPAD28                       TP183
ZZ.PAD28.XXX       TPAD28                       TP184
ZZ.PAD28.XXX       TPAD28                       TP185
ZZ.PAD28.XXX       TPAD28                       TP186
ZZ.PAD28.XXX       TPAD28                       TP187
ZZ.PAD28.XXX       TPAD28                       TP188
ZZ.PAD28.XXX       TPAD28                       TP189
ZZ.PAD28.XXX       TPAD28                       TP190
ZZ.PAD28.XXX       TPAD28                       TP191
ZZ.PAD28.XXX       TPAD28                       TP192
ZZ.PAD28.XXX       TPAD28                       TP193
020.F0528.0011     91932-31111LF                TPM1
19-000387$AA       BGA896D25H78                 U1
071.02500.0B0U     BGA456D19H58                 U2
73.02G07.A2J       SOT-363H44                   U5
73.01G07.01H       SC70-5H44                    U9
74.00331.A2F       SC70-5H44                    U10
072.25256.0B01     SOIC16-6H104                 U11
073.03166.000B     SC70-5H44                    U12
073.03166.000B     SC70-5H44                    U15
073.03166.000B     SC70-5H44                    U16
073.01G74.0001     SSOIC8-4H36                  U19
72.02464.A01       SOIC8H69                     U26
74.00075.B79       MSOP8-1H44                   U27
072.00546.0A0U     BGA96D075130H48              U28
72.25635.A01       SOIC16-6H105                 U29
71.00551.00A       SOIC8H69                     U30
73.01G08.L03       SC70-5H44                    U31
73.74126.BHB       SSOIC14-1H48                 U32
74.23157.A99       MSOP10H44                    U33
071.09555.000W     TSOIC24H48                   U34
074.01278.0A7Z     QFN32-G3D45-UH32             U35
73.01G08.L03       SC70-5H44                    U36
73.01G08.L03       SC70-5H44                    U37
72.24C64.I01       SOIC8H69                     U38
74.03808.073       DFN6F2-G1711-UH32            U41
72.29128.Z09       TSOP56-1H48                  U42
71.09306.00I       SSOIC8H52                    U43
73.00102.007       SSOIC8-4H36                  U44
71.09306.00I       SSOIC8H52                    U45
73.01G08.L03       SC70-5H44                    U46
73.01G86.DHH       SC70-5H44                    U47
73.01G08.L03       SC70-5H44                    U48
73.01G08.L03       SC70-5H44                    U49
73.01G86.DHH       SC70-5H44                    U50
73.01G08.L03       SC70-5H44                    U51
73.01G08.L03       SC70-5H44                    U52
73.01G07.EHH       SC70-5H44                    U95
74.02065.07F       SOT-23-5H58                  U98
71.02514.F03       QFN36-G3D85H40               U99
73.1G126.DHG       SC70-5H44                    U100
73.1G126.DHG       SC70-5H44                    U101
73.01G14.L05       SC70-5H44                    U102
73.1G126.DHG       SC70-5H44                    U103
73.1G126.DHG       SC70-5H44                    U104
73.03245.F0B       TSOIC20H48                   U105
73.01G14.AHG       SOT-23-5H58                  U106
73.03245.F0B       TSOIC20H48                   U107
022.10005.0I61     SKT-USB13-064258             USB1
ZZ.00PAD.MP1       VIA-PCIE-4P-368076           VIA1
ZZ.00PAD.MP1       VIA-PCIE-4P-368076           VIA2
ZZ.00PAD.MP1       VIA-PCIE-4P-368076           VIA3
ZZ.00PAD.MP1       VIA-PCIE-4P-368076           VIA4
ZZ.00PAD.MP1       VIA-PCIE-4P-368076           VIA5
ZZ.00PAD.MP1       VIA-PCIE-4P-368076           VIA6
ZZ.00PAD.MP1       VIA-PCIE-4P-368076           VIA7
ZZ.00PAD.MP1       VIA-PCIE-4P-368076           VIA8
ZZ.00PAD.MP1       VIA-PCIE-4P-368076           VIA9
ZZ.00PAD.MP1       VIA-PCIE-4P-368076           VIA10
ZZ.00PAD.MP1       VIA-PCIE-4P-368076           VIA11
ZZ.00PAD.MP1       VIA-PCIE-4P-368076           VIA12
ZZ.00PAD.MP1       VIA-PCIE-4P-368076           VIA13
ZZ.00PAD.MP1       VIA-PCIE-4P-368076           VIA14
ZZ.00PAD.MP1       VIA-PCIE-4P-368076           VIA15
ZZ.00PAD.MP1       VIA-PCIE-4P-368076           VIA16
ZZ.00PAD.MP1       VIA-PCIE-4P-368076           VIA17
ZZ.00PAD.MP1       VIA-PCIE-4P-368076           VIA18
ZZ.00PAD.MP1       VIA-PCIE-4P-368076           VIA19
ZZ.00PAD.MP1       VIA-PCIE-4P-368076           VIA20
ZZ.00PAD.MP1       VIA-PCIE-4P-368076           VIA21
ZZ.00PAD.MP1       VIA-PCIE-4P-368076           VIA22
ZZ.00PAD.MP1       VIA-PCIE-4P-368076           VIA23
ZZ.00PAD.MP1       VIA-PCIE-4P-368076           VIA24
ZZ.00PAD.MP1       VIA-PCIE-4P-368076           VIA25
ZZ.00PAD.MP1       VIA-PCIE-4P-368076           VIA26
ZZ.00PAD.NB1       VIA-PCIE-4P-394076           VIA41
ZZ.00PAD.NB1       VIA-PCIE-4P-394076           VIA42
ZZ.00PAD.NB1       VIA-PCIE-4P-394076           VIA43
ZZ.00PAD.NB1       VIA-PCIE-4P-394076           VIA44
ZZ.00PAD.NB1       VIA-PCIE-4P-394076           VIA45
ZZ.00PAD.NB1       VIA-PCIE-4P-394076           VIA46
ZZ.00PAD.NB1       VIA-PCIE-4P-394076           VIA47
ZZ.00PAD.NB1       VIA-PCIE-4P-394076           VIA48
82.30004.901       OSC-3225-4P-4H30             X1
82.20043.221       OSC-3225-4P-3H48             X2

EOS

POSITION

C1        3451.75     1157.10     180.000    TOP
C2        3720.00     1110.00      90.000    TOP
C8        3818.14     6290.80      90.000    BOT
C9        3676.20     6013.64     180.000    BOT
C10       3618.00     6017.00     180.000    BOT
C11       3671.13     6245.07       0.000    BOT
C12       3530.00     6126.00      90.000    BOT
C13       3756.00     6014.00     180.000    BOT
C14       3564.80     5886.40       0.000    BOT
C15       3492.00     6349.00     180.000    BOT
C16       3540.00     6349.00     180.000    BOT
C17       3607.86     6398.80     270.000    TOP
C18       3699.69     5835.58       0.000    TOP
C19       3529.80     6391.14     180.000    TOP
C20       3684.14     6398.20      90.000    TOP
C21       3720.00     1160.00      90.000    TOP
C22       3720.00     1210.00      90.000    TOP
C25       3248.48     1919.94     270.000    BOT
C26        846.16      576.75     180.000    TOP
C27       2650.05     5495.94     270.000    BOT
C28       3122.72     1965.44     180.000    BOT
C29       3275.52     2213.84       0.000    BOT
C30       3222.77     5504.43     180.000    TOP
C31        434.80      509.50     180.000    TOP
C32       2925.00     5430.00     270.000    TOP
C33       2452.00     6901.00     180.000    BOT
C34       2630.00     6775.00       0.000    TOP
C35       2606.00     6698.00     270.000    TOP
C36       1813.18     4637.48      90.000    TOP
C37       3700.00     6895.00      90.000    BOT
C38       2609.00     6661.00      90.000    TOP
C39       3676.00     7037.00     180.000    BOT
C40       3286.59     5378.59       0.000    TOP
C41       3896.00     7007.00      90.000    BOT
C44       3360.00     5920.00      90.000    TOP
C49       2024.86     6983.55     270.000    TOP
C50       2474.00     6412.00       0.000    TOP
C51       3790.00     5432.00     270.000    TOP
C52       2706.00     6390.00      90.000    TOP
C53       1737.69     5799.40      90.000    BOT
C54       1411.89     5935.37     180.000    BOT
C55       1737.79     5833.87     270.000    BOT
C56       1783.48     5682.51      90.000    BOT
C57       1354.49     5627.49     180.000    BOT
C58       1512.57     5632.23       0.000    BOT
C59       1465.67     5631.91       0.000    BOT
C60       1418.87     5632.91       0.000    BOT
C61        520.50     5802.50     270.000    BOT
C62        643.50     5797.00     180.000    BOT
C63        503.00     5863.50     270.000    BOT
C64       1026.74     5358.24      90.000    BOT
C65        446.68     5673.16     270.000    BOT
C66        782.31     5641.99     180.000    BOT
C67        928.70     5662.15     180.000    BOT
C68        654.00     5478.00     180.000    BOT
C69        971.13     5661.86     180.000    BOT
C70       1006.19     5661.85     180.000    BOT
C71       1505.16     5703.04     270.000    BOT
C72        962.87     5746.99       0.000    BOT
C73       1019.30     5764.52      90.000    BOT
C74       2701.00     4654.00      90.000    TOP
C75       2999.00     5840.00     180.000    TOP
C76       2965.00     5840.00     180.000    TOP
C78       2826.00     6839.00     180.000    TOP
C79       1177.00     5170.00       0.000    TOP
C80       2526.70     6222.37     180.000    BOT
C81       2470.70     6229.40     180.000    BOT
C82       2533.00     5902.00      90.000    TOP
C83       1932.50     5592.50     270.000    BOT
C84       2105.20     6311.10       0.000    TOP
C85       2036.50     6348.50       0.000    TOP
C86       2070.60     6314.20       0.000    TOP
C87       2197.50     6091.50      90.000    BOT
C88       2175.20     6050.70      90.000    BOT
C89       1887.10     6220.20      90.000    BOT
C90       1878.80     6155.40      90.000    BOT
C91       1859.20     6112.40      90.000    BOT
C92       1291.00     5943.00     180.000    BOT
C93       1336.00     5938.00     180.000    BOT
C94       1371.00     5938.00     180.000    BOT
C95       2283.84     6244.09     180.000    BOT
C96       2243.46     6237.95     180.000    BOT
C97       1534.95     5523.66     180.000    BOT
C98       1972.59     5774.97     270.000    BOT
C99       1488.40     5523.35     180.000    BOT
C100      1824.00     5592.00      90.000    BOT
C101      1998.30     5834.40     270.000    BOT
C102      1772.60     6153.80     270.000    BOT
C103      1774.60     6111.80     270.000    BOT
C104      1440.37     5522.86       0.000    BOT
C105      1774.60     6074.80     270.000    BOT
C106      1378.24     5485.46     180.000    BOT
C107      1892.89     5826.25      90.000    BOT
C108      1815.05     5785.91       0.000    BOT
C109      2047.00     5222.00       0.000    BOT
C110      1954.00     5223.00       0.000    BOT
C113      2000.55     5221.51       0.000    BOT
C114      2141.00     5223.00       0.000    BOT
C115      2094.45     5222.49     180.000    BOT
C116      2203.00     5219.00       0.000    BOT
C117      2135.00     6384.00      90.000    BOT
C118      2154.06     6396.92     180.000    TOP
C119      2346.00     6339.00     270.000    BOT
C120      2275.00     6438.00     180.000    TOP
C121      2055.50     6334.50     270.000    BOT
C122      2079.00     6397.00     180.000    TOP
C123      2238.19     6341.88      90.000    BOT
C124      2129.00     6495.00      90.000    BOT
C125      3235.00     6819.00      90.000    BOT
C126      3654.00     5098.00     180.000    BOT
C127      3785.00     5765.00       0.000    BOT
C128      4538.00      587.00     180.000    TOP
C129      4773.00      630.00     180.000    TOP
C130      4915.86      379.07      90.000    TOP
C131      4443.35      343.57     270.000    TOP
C132      4730.00      255.00      90.000    BOT
C133      4700.16      537.45      90.000    TOP
C134      5218.00      516.00       0.000    TOP
C135      3011.19     5536.53     270.000    TOP
C136      3520.30     7026.20     270.000    TOP
C137      3672.89     5540.00     270.000    BOT
C138      5382.50      702.90     180.000    TOP
C139      5339.40      704.10     180.000    TOP
C141      3869.70     6971.80      90.000    TOP
C144      4960.00      534.15       0.000    BOT
C145      5078.95      575.97       0.000    BOT
C146      5026.22      251.93       0.000    TOP
C147      4373.00      475.57     270.000    TOP
C148      4373.00      426.57     270.000    TOP
C149      4373.00      524.57     270.000    TOP
C150      4459.00      347.00       0.000    BOT
C151      6809.00     5366.00     270.000    TOP
C152      6808.76     5443.29     270.000    TOP
C153      6808.76     5520.29     270.000    TOP
C154      6792.00     5674.00     270.000    TOP
C155      6808.76     5597.29     270.000    TOP
C156      7193.00     6037.00      90.000    TOP
C157      7011.76     5544.29      90.000    BOT
C158      6968.99     6075.58     270.000    BOT
C159      6761.94     5879.29       0.000    TOP
C160      7110.00     6190.00      90.000    TOP
C161      7062.00     5583.00     270.000    TOP
C162      7236.76     5894.29       0.000    TOP
C163      7276.76     5894.29     180.000    TOP
C164      6655.00     7042.00     270.000    TOP
C165      6655.00     6965.00     270.000    TOP
C166      6655.00     6888.00     270.000    TOP
C167      6661.00     6532.00     270.000    TOP
C168      6661.00     6734.00     270.000    TOP
C169      2254.00     7148.00       0.000    TOP
C170      1017.49     7345.15     180.000    TOP
C171       940.20     7344.91     180.000    TOP
C172      2196.00     7139.00       0.000    TOP
C173      1248.20     7361.91     180.000    TOP
C174      2118.00     7139.00       0.000    TOP
C175      1979.20     7244.91       0.000    TOP
C176      1094.49     7345.15     180.000    TOP
C177      1171.49     7345.15     180.000    TOP
C178      1609.64     7202.68       0.000    BOT
C179       963.00     7057.00     270.000    BOT
C180      1448.49     7400.15     270.000    TOP
C181      1701.00     7064.00       0.000    TOP
C182      1156.19     7099.95     180.000    TOP
C183      1469.00     6916.00     270.000    TOP
C184      1468.49     6877.15      90.000    TOP
C185      3666.99     2030.21       0.000    TOP
C186      3539.72     1899.44     180.000    TOP
C187      3142.49     2214.07      90.000    BOT
C188      3142.79     2291.57      90.000    BOT
C189      3439.00     1898.74      90.000    TOP
C190      2930.04     6881.20     270.000    TOP
C191      3245.74     6912.70      90.000    TOP
C192      3214.70     7025.74     180.000    TOP
C193      3136.70     7026.74     180.000    TOP
C194      3245.74     6833.70      90.000    TOP
C195      3149.20     6807.20       0.000    TOP
C196      2725.03     7065.37     180.000    TOP
C197      2785.23     7334.05     180.000    TOP
C198      3117.04     7139.20       0.000    TOP
C199      2984.70     7349.74     180.000    TOP
C200      3063.70     7349.74     180.000    TOP
C201      2738.00     7151.00     270.000    TOP
C202      6471.00     5403.00      90.000    TOP
C203      6453.00     5280.00       0.000    TOP
C204      6515.00     5270.00       0.000    TOP
C205      6596.00     5270.00       0.000    TOP
C206      6411.00     5575.00     270.000    TOP
C207      6326.60     5215.43     270.000    TOP
C208      6236.60     5549.43     270.000    TOP
C209      6281.60     5625.43     180.000    TOP
C210      6119.10     5215.43     270.000    TOP
C211      6497.00     4996.00      90.000    TOP
C212      6450.00     5547.00     180.000    BOT
C213      6125.00     5378.00     180.000    TOP
C214      6185.00     4670.00     270.000    TOP
C215      6185.00     4730.00     270.000    TOP
C216      6185.00     4810.00     270.000    BOT
C217      6185.00     4810.00     270.000    TOP
C218      6185.00     4730.00     270.000    BOT
C219      6751.74     4620.79       0.000    TOP
C220      6638.00     4369.00     270.000    TOP
C221      6792.00     4610.00     180.000    TOP
C222       630.84     6439.00     270.000    TOP
C223       837.50     6584.54     180.000    TOP
C224       915.50     6583.54     180.000    TOP
C225       946.54     6391.50      90.000    TOP
C226       946.54     6470.50      90.000    TOP
C227       855.00     6345.00       0.000    TOP
C228       456.00     6607.00      90.000    TOP
C229       718.00     6887.00     180.000    TOP
C230       817.84     6697.00       0.000    TOP
C231       908.50     6821.54      90.000    TOP
C232       909.00     6744.00      90.000    TOP
C233       499.00     6731.84       0.000    TOP
C234      3038.70     6123.50     270.000    TOP
C235      3246.36     6314.04     180.000    TOP
C236      3265.40     6115.00      90.000    TOP
C237      3324.36     6313.04     180.000    TOP
C238      3265.40     6194.00      90.000    TOP
C239      3176.00     6086.00       0.000    TOP
C240      2802.73     6376.55      90.000    TOP
C241      2950.18     6585.82     180.000    TOP
C242      3221.00     6435.00       0.000    TOP
C243      3195.36     6623.04     180.000    TOP
C244      3116.36     6623.04     180.000    TOP
C245      2836.60     6442.50     270.000    TOP
C246      8077.00     4772.00     270.000    TOP
C247      8394.00     4815.00      90.000    BOT
C248      8282.50     4927.54     180.000    TOP
C249      8360.50     4926.54     180.000    TOP
C250      8394.54     4816.50      90.000    TOP
C251      8394.00     4755.00      90.000    TOP
C252      7945.00     4994.00       0.000    TOP
C253      8003.88     5201.56     180.000    TOP
C254      8262.84     5037.00       0.000    TOP
C255      8210.50     5234.54     180.000    TOP
C256      8131.50     5234.54     180.000    TOP
C257      7940.88     5104.12     180.000    TOP
C258      7814.00     4469.00     180.000    TOP
C259      7903.00     4469.00     180.000    TOP
C260      7866.00     4470.00     180.000    BOT
C261      7776.00     4470.00     180.000    BOT
C262      7866.00     4180.00       0.000    TOP
C263      7825.00     4180.00       0.000    TOP
C264      7584.35     4164.73       0.000    TOP
C265      7497.00     4165.00       0.000    TOP
C266      7671.35     4164.73       0.000    TOP
C267      7624.00     4759.00       0.000    TOP
C268      7758.35     4164.73       0.000    TOP
C269      7251.00     4335.00      90.000    TOP
C270      7251.00     4647.00      90.000    TOP
C271      7251.00     4413.00      90.000    TOP
C272      7251.00     4491.00      90.000    TOP
C273      7251.00     4647.00      90.000    BOT
C274      7251.00     4569.00      90.000    TOP
C275      7251.00     4569.00      90.000    BOT
C276      7285.59     4760.98       0.000    TOP
C277      7249.00     4910.00     180.000    TOP
C278      7202.00     4910.00     180.000    TOP
C279      7638.01     4905.19     180.000    TOP
C280      7570.99     5247.66       0.000    TOP
C281      7553.00     5025.00     180.000    TOP
C282      7655.00     4838.00      90.000    TOP
C283      7496.00     4749.00     270.000    BOT
C284      7631.47     4981.27     180.000    TOP
C285      7672.47     4996.27     180.000    TOP
C286      7599.00     4896.00     180.000    BOT
C287      7475.00     5027.00     180.000    TOP
C288      7080.00     4545.00       0.000    TOP
C289      7938.17     3195.00     180.000    BOT
C290      7916.17     3195.00     180.000    BOT
C291      7888.17     3195.00     180.000    BOT
C292      7866.17     3195.00     180.000    BOT
C293      7838.17     3195.00     180.000    BOT
C294      7816.17     3195.00     180.000    BOT
C295      7788.17     3195.00     180.000    BOT
C296      7766.17     3195.00     180.000    BOT
C297      7618.17     3195.00     180.000    BOT
C298      7596.17     3195.00     180.000    BOT
C299      7568.17     3195.00     180.000    BOT
C300      7546.17     3195.00     180.000    BOT
C301      7488.17     3195.00     180.000    BOT
C302      7466.17     3195.00     180.000    BOT
C303      7423.17     3195.00     180.000    BOT
C304      7401.17     3195.00     180.000    BOT
C305      8828.71     2380.12     180.000    TOP
C306      8831.00     2229.00       0.000    TOP
C307      8191.18     3020.00      90.000    TOP
C308      8191.18     2998.00      90.000    TOP
C309      8191.18     2954.00      90.000    TOP
C310      8191.18     2932.00      90.000    TOP
C311      8191.18     2888.00      90.000    TOP
C312      8191.18     2866.00      90.000    TOP
C313      8191.18     2822.00      90.000    TOP
C314      8191.18     2800.00      90.000    TOP
C315      8191.18     2756.00      90.000    TOP
C316      8191.18     2734.00      90.000    TOP
C317      8191.18     2690.00      90.000    TOP
C318      8191.18     2668.00      90.000    TOP
C319      8191.18     2624.00      90.000    TOP
C320      8191.18     2602.00      90.000    TOP
C321      8191.18     2558.00      90.000    TOP
C322      8191.18     2536.00      90.000    TOP
C323      8162.34     3897.02     270.000    TOP
C324      8334.00     4392.00     180.000    TOP
C325      3677.62     1434.01     180.000    TOP
C327      6115.00     3589.00      90.000    BOT
C328      6486.98     2980.89       0.000    BOT
C329      6475.00     2016.00       0.000    BOT
C330      7603.00     1852.00     270.000    BOT
C331      7575.00     1993.00     270.000    BOT
C332      7575.00     1915.00     270.000    BOT
C333      7594.00     2043.00     270.000    BOT
C334      7920.37     2025.18     270.000    BOT
C335      7920.37     1960.18     270.000    BOT
C336      7917.02     2060.42     270.000    BOT
C337      7917.02     2085.42     270.000    BOT
C338      8063.62     2024.83     270.000    BOT
C339      8063.62     1959.83     270.000    BOT
C340      8061.56     2083.63     270.000    BOT
C341      8062.16     2060.45     270.000    BOT
C342      6857.00     3068.00     180.000    BOT
C343      6795.00     3065.00     180.000    BOT
C344      6920.00     3070.00     180.000    BOT
C345      6895.00     3070.00     180.000    BOT
C346      7778.00     2025.00     270.000    BOT
C347      7778.00     1960.00     270.000    BOT
C348      7778.00     2087.00     270.000    BOT
C349      7778.00     2065.00     270.000    BOT
C350      8340.00     3325.00      90.000    BOT
C351      8340.00     3390.00      90.000    BOT
C352      8047.68     2706.64     270.000    BOT
C353      8049.68     2784.64     270.000    BOT
C354      7891.00     2690.00      90.000    BOT
C355      7885.00     2805.00     270.000    BOT
C356      7947.26     3655.56     180.000    BOT
C357      8012.26     3655.56     180.000    BOT
C358      7648.79     2849.64     270.000    BOT
C359      7520.00     2871.00       0.000    BOT
C360      7769.90     2848.20      90.000    BOT
C361      7873.93     2858.00      90.000    BOT
C362      6999.25     3186.94       0.000    BOT
C363      6906.20     3209.40     180.000    BOT
C364      7752.00     2797.00       0.000    BOT
C365      7908.00     2966.00       0.000    BOT
C366      7548.00     2768.50       0.000    BOT
C367      7595.08     2849.64     270.000    BOT
C368      7815.10     2760.20      90.000    BOT
C369      7812.00     2799.80      90.000    BOT
C370      7708.00     3010.00       0.000    BOT
C371      7570.00     2768.50       0.000    BOT
C372      7777.00     3084.00     180.000    BOT
C373      8649.28     3875.92       0.000    TOP
C374      8736.23     3875.38       0.000    TOP
C375      7815.80     2608.40       0.000    BOT
C376      8005.00     3095.00      90.000    BOT
C377      8005.00     3070.00      90.000    BOT
C378      8031.00     2917.00       0.000    BOT
C379      8049.00     2738.00      90.000    BOT
C380      7864.90     2660.10      90.000    BOT
C381      7868.80     2609.90       0.000    BOT
C382      7871.20     2830.30      90.000    BOT
C383      7806.40     2690.30     270.000    BOT
C384      7703.00     2738.00     180.000    BOT
C385      7764.10     2419.50      90.000    BOT
C386      7700.90     2230.80       0.000    BOT
C387      7354.00     2611.50     270.000    BOT
C388      7606.50     2322.70       0.000    BOT
C389      7416.50     2318.00       0.000    BOT
C390      7714.00     2624.50      90.000    BOT
C391      7765.90     2478.80      90.000    BOT
C392      7263.50     3208.80       0.000    BOT
C393      7223.90     3208.60       0.000    BOT
C394      7185.90     3208.60       0.000    BOT
C395      7767.50     2518.50      90.000    BOT
C396      7512.50     2552.00      90.000    BOT
C397      7743.50     2563.50     180.000    BOT
C398      7514.00     2489.00      90.000    BOT
C399      7451.00     2574.00      90.000    BOT
C400      7637.00     2552.00      90.000    BOT
C401      7637.00     2574.00      90.000    BOT
C402      7698.00     2551.50      90.000    BOT
C403      7636.50     2489.00      90.000    BOT
C404      7451.50     2448.50      90.000    BOT
C405      7698.00     2573.50      90.000    BOT
C406      7575.00     2574.00      90.000    BOT
C407      7636.50     2511.00      90.000    BOT
C408      7575.00     2426.00      90.000    BOT
C409      7700.50     2489.40      90.000    BOT
C410      7575.00     2448.00      90.000    BOT
C411      7451.50     2426.00      90.000    BOT
C412      7451.00     2552.00      90.000    BOT
C413      7514.00     2511.00      90.000    BOT
C414      7513.07     2448.05      90.000    BOT
C415      7513.00     2426.00      90.000    BOT
C416      7575.00     2552.00      90.000    BOT
C417      7512.50     2574.00      90.000    BOT
C418      7575.50     2489.00      90.000    BOT
C419      7575.50     2511.00      90.000    BOT
C420      7637.00     2426.00      90.000    BOT
C421      7637.00     2448.00      90.000    BOT
C422      7700.50     2511.40      90.000    BOT
C423      7542.50     2689.00     270.000    BOT
C424      7641.00     2622.50      90.000    BOT
C425      7553.00     2623.50     270.000    BOT
C426      7448.50     2499.00      90.000    BOT
C427      7627.00     2690.00      90.000    BOT
C428      7733.00     2339.00      90.000    BOT
C429      7464.50     2689.00     270.000    BOT
C430      7478.00     2623.50     270.000    BOT
C431      7321.70     2274.00      90.000    BOT
C432      7401.00     2188.00      90.000    BOT
C433      7476.00     2188.00      90.000    BOT
C434      7649.00     2120.00       0.000    BOT
C435      7792.00     2181.00      90.000    BOT
C436      7867.19     2180.74      90.000    BOT
C437      7992.00     2163.50       0.000    BOT
C438      7792.00     2147.00      90.000    BOT
C439      7903.60     2412.00     180.000    BOT
C440      7889.50     2347.70     270.000    BOT
C441      7891.00     2244.00     270.000    BOT
C442      7957.19     2163.24       0.000    BOT
C443      7889.50     2313.50     270.000    BOT
C444      7321.60     2308.40      90.000    BOT
C445      7889.50     2279.00     270.000    BOT
C446      8062.10     2163.40       0.000    BOT
C447      6640.00     4215.00     270.000    BOT
C448      6640.00     4175.00     270.000    BOT
C449      6640.00     4135.00     270.000    BOT
C450      7479.68     2944.64      90.000    BOT
C451      7343.20     2881.50      90.000    BOT
C452      7418.60     2878.10      90.000    BOT
C453      8026.50     2163.30       0.000    BOT
C454      7970.99     2415.45       0.000    BOT
C455      7968.29     2323.25       0.000    BOT
C456      8026.00     2468.00      90.000    BOT
C457      6640.00     4260.00     270.000    BOT
C458      7922.69     2162.94       0.000    BOT
C459      7684.79     2104.64       0.000    BOT
C460      7590.00     2129.00       0.000    BOT
C461      6639.00     4094.00     270.000    TOP
C462      6639.00     4135.00     270.000    TOP
C463      6639.00     4176.00     270.000    TOP
C464      6639.00     4217.00     270.000    TOP
C465      6639.00     4258.00     270.000    TOP
C466      6639.00     4299.00     270.000    TOP
C467      7269.00     2752.00      90.000    BOT
C468      7214.00     2800.00     180.000    BOT
C469      7291.50     2842.10      90.000    BOT
C470      7254.68     2944.64     270.000    BOT
C471      7329.68     2944.64     270.000    BOT
C472      7404.68     2944.64     270.000    BOT
C473      7248.63     2687.02      90.000    BOT
C474      7245.00     2623.00      90.000    BOT
C475      7246.50     2565.50      90.000    BOT
C476      7249.40     2498.50      90.000    BOT
C477      7251.70     2437.00      90.000    BOT
C478      7246.29     2377.14      90.000    BOT
C479      7243.50     2314.60      90.000    BOT
C480      7245.60     2250.60      90.000    BOT
C481      6338.00     3397.00       0.000    TOP
C482      6285.22     3681.28     270.000    TOP
C483      6140.00     3391.00       0.000    TOP
C484      6170.23     3741.65     180.000    TOP
C485      3268.86     5225.25      90.000    TOP
C486      7546.85      860.00     270.000    BOT
C487      7546.85      780.00     270.000    BOT
C488      7546.85      755.00     270.000    BOT
C489      7546.85      835.00     270.000    BOT
C490      7546.84     1020.00     270.000    BOT
C491      7546.84      995.00     270.000    BOT
C492      7546.85      940.00     270.000    BOT
C493      7546.85      915.00     270.000    BOT
C494      6666.85     1513.47       0.000    BOT
C495      6612.84     1513.47       0.000    BOT
C496      6637.84     1513.47       0.000    BOT
C497      6691.85     1513.47       0.000    BOT
C498      6508.84     1512.47       0.000    BOT
C499      6533.84     1512.47       0.000    BOT
C500      6560.85     1512.47       0.000    BOT
C501      6585.85     1512.47       0.000    BOT
C502      3079.00     5125.00       0.000    BOT
C503      3566.00     5226.00       0.000    BOT
C504      3578.00     5414.00     270.000    BOT
C505      2075.00     4973.80     180.000    BOT
C506      1641.35     4817.62     270.000    BOT
C507      3666.32     1946.04     180.000    TOP
C508      1121.00     4973.00     270.000    BOT
C509      8082.00     4392.00     180.000    TOP
C510      7024.60     4828.50       0.000    TOP
C511      3248.22     1842.94     270.000    BOT
C512      3276.12     2355.54     180.000    BOT
C513      2966.00     5247.50     270.000    TOP
C514      7762.00      530.00       0.000    TOP
C515      7677.00     1130.00      90.000    TOP
C516      7758.00      660.00      90.000    TOP
C517      5592.00      423.00       0.000    TOP
C518      2615.07     6262.53      90.000    TOP
C519      2124.45     6552.88     180.000    TOP
C520      2005.32     6554.03     180.000    TOP
C521      5590.00      647.00     270.000    BOT
C522      3608.00     4935.00     180.000    TOP
C523      5828.00      774.00     270.000    BOT
C524      2999.00     6591.00     180.000    TOP
C525      3750.00      245.00      90.000    BOT
C526      7611.80     1198.60      90.000    TOP
C527      6324.60     1590.80     180.000    TOP
C528       710.90      578.00     180.000    TOP
C529       509.60      528.30     180.000    TOP
C744      7428.30     4527.00     270.000    TOP
C998      1879.30     5520.00     270.000    BOT
C999      2029.70     5525.00      90.000    BOT
CA1       4779.43      379.65     180.000    BOT
CN1       5562.99     1740.16     180.000    TOP
CN5       6003.00     5744.00       0.000    TOP
D1        5255.20      704.90       0.000    TOP
D2         936.40      578.60       0.000    TOP
D3         340.70      510.70       0.000    TOP
D4        3614.92     2327.24      90.000    TOP
D5        7103.30     4905.70     180.000    TOP
D11       2787.00     6636.00     270.000    TOP
D13       3449.58     1085.78     180.000    TOP
D14       3732.68      492.23      90.000    TOP
D15       3732.68      538.23      90.000    TOP
D16       3730.94      800.95      90.000    TOP
D17       3730.94      846.95      90.000    TOP
D18       3720.00      640.00     180.000    TOP
D19       3720.00      704.00       0.000    TOP
EXT1      7086.61      578.74       0.000    TOP
EXT2      6299.21      578.74       0.000    TOP
G1        6685.00     7098.00      90.000    TOP
G2        7199.00     5763.00     270.000    TOP
G3        1347.00     6961.00     180.000    TOP
G4        6160.00     4630.00     180.000    TOP
G5        6160.00     5554.00     270.000    TOP
L1        3886.27      704.90      90.000    TOP
L2        2236.40     6153.20     270.000    BOT
L3        1226.00     5936.00       0.000    BOT
L4        2393.46     6230.76     180.000    BOT
L5        1746.30     6219.90      90.000    BOT
L6        6920.00     5333.00     180.000    TOP
L7        6798.00     6172.00     180.000    TOP
L8         917.00     7227.00      90.000    TOP
L9        1676.00     7285.00      90.000    TOP
L10       6251.00     5022.00       0.000    TOP
L11       7122.89     4229.09       0.000    TOP
L12       7618.00     4500.84       0.000    TOP
L13       7626.00     1749.00     270.000    BOT
L14       7920.37     1882.18     270.000    BOT
L15       8063.62     1880.83     270.000    BOT
L16       6684.00     3013.00     270.000    BOT
L17       7775.00     1882.00     270.000    BOT
L18       8340.00     3470.00      90.000    BOT
L19       8093.26     3654.56     180.000    BOT
L20       7127.80     3206.40       0.000    BOT
L21       8936.34     3811.59       0.000    TOP
L23       3560.00     1057.00      90.000    TOP
LED2      7637.80      244.09       0.000    TOP
LED3      5748.03      244.09       0.000    TOP
LED4      8855.62     3107.55       0.000    TOP
LED5      6463.77     4095.37       0.000    TOP
LED6       936.14     5043.52     180.000    TOP
LED7      8110.24      244.09       0.000    TOP
MEZZ1     3059.06     2856.30     270.000    TOP
NUT1      1631.89     6692.91       0.000    TOP
OSC1      1304.00     5178.00       0.000    TOP
P1        4930.35      420.57     270.000    TOP
PQ1       4954.90      636.70      90.000    TOP
PQ2       3637.26     1836.81      90.000    TOP
PQ3       3491.11     2103.64       0.000    TOP
PQ4       6867.50     4733.84      90.000    TOP
PQ5       6585.46     4568.21      90.000    TOP
PSP1      7347.19     4812.47     270.000    BOT
PU1       7005.46     5775.99       0.000    TOP
PU2       1350.19     7148.45     270.000    TOP
PU4       6271.60     5380.43       0.000    TOP
PU7       8102.14     4998.50     270.000    TOP
PU8       7438.22     4803.58      90.000    TOP
PU9       2956.34     7100.70     270.000    TOP
PU10       657.14     6658.50     270.000    TOP
PU11      3063.00     6386.00     270.000    TOP
PWR1       944.88      344.49       0.000    TOP
Q2        2635.00     6525.00     270.000    TOP
Q3        2485.00     6525.00      90.000    TOP
Q4        2485.00     6665.00      90.000    TOP
Q5        5290.93      320.85     270.000    TOP
Q6        6923.50     4897.16     270.000    TOP
Q7        6765.00     4895.00     270.000    TOP
Q8        7865.84     5287.50     180.000    TOP
Q9        7676.84     5282.50     180.000    TOP
Q11       3468.81     6603.05       0.000    TOP
Q12       3314.36     6602.30       0.000    TOP
Q14       8973.44     3030.41       0.000    TOP
Q15       6462.20     3952.44       0.000    TOP
Q16       6038.73     3832.11     180.000    TOP
Q17       5898.73     3832.11     180.000    TOP
Q20       4703.00      618.00      90.000    BOT
Q21       7870.00      705.00       0.000    TOP
Q22       5595.00      725.00       0.000    TOP
Q24       7867.50      898.00       0.000    TOP
Q25       3362.82     3902.43     180.000    BOT
Q26       3701.00     5633.38     270.000    BOT
Q27       7856.00     1138.50       0.000    TOP
Q28       8110.41      532.52      90.000    TOP
Q29       8262.20      613.00     270.000    TOP
Q205      5736.00      588.00       0.000    TOP
Q206      7627.00      540.45       0.000    TOP
R3        3419.47     2269.92     270.000    TOP
R4        3419.17     2311.56      90.000    TOP
R5        3473.31     2422.61     270.000    TOP
R7        3474.22     2473.14     270.000    TOP
R8        3419.82     2564.74     270.000    TOP
R9        3419.59     2611.12      90.000    TOP
R10       3490.04     1813.30     180.000    TOP
R14       3444.94     2685.85     270.000    TOP
R15       3447.91     2729.06     270.000    TOP
R16       3398.51     1812.17       0.000    TOP
R18       3894.36     6197.01     270.000    TOP
R19       3894.00     6062.00     270.000    TOP
R20       3892.86     6280.81     270.000    TOP
R21       3727.84     6260.32      90.000    BOT
R22       3774.16     6205.03     270.000    BOT
R23       3894.00     6103.00      90.000    TOP
R24       3608.20     5885.36     180.000    TOP
R25       3566.80     5873.64       0.000    TOP
R26       3894.81     6237.86      90.000    TOP
R27       3643.64     6359.20      90.000    TOP
R28       3486.00     6373.00     180.000    TOP
R29       3825.50     5831.06     180.000    TOP
R30       3893.00     5895.71     270.000    TOP
R31       3894.00     6021.00     270.000    TOP
R32       3892.50     6373.48     270.000    TOP
R33       3524.80     5878.64     180.000    TOP
R34       3783.50     5831.06     180.000    TOP
R35       3882.79     5855.43     270.000    TOP
R36       3921.33     5961.90       0.000    TOP
R37       3755.00      310.00      90.000    BOT
R38       3912.62      705.71     180.000    TOP
R39       7560.20     1265.10      90.000    TOP
R40       3524.80     5878.64       0.000    BOT
R41       3742.92     5851.00       0.000    TOP
R42       3800.00     6001.00     180.000    BOT
R43       3877.33     5962.90     180.000    TOP
R44       6390.40     1594.10     180.000    TOP
R45        795.70      567.60     180.000    TOP
R46       3860.27      705.40     180.000    TOP
R47        580.10      508.10     180.000    TOP
R48        890.34      576.35       0.000    TOP
R49       2625.00     5395.00      90.000    TOP
R50       3284.80     5313.80     270.000    TOP
R51       2931.55     5469.06     270.000    TOP
R52       2696.00     5298.00       0.000    TOP
R53       3288.21     5263.09     270.000    TOP
R54       2971.75     5367.54       0.000    TOP
R56       2659.00     5521.00      90.000    TOP
R58       2932.00     5513.00     270.000    TOP
R59       2655.41     5437.59     270.000    TOP
R64       3271.74     3876.18     180.000    BOT
R65        387.80      497.60       0.000    TOP
R71       2519.00     6780.00     180.000    TOP
R72       2434.00     6412.00     180.000    TOP
R73       2683.00     6430.00     270.000    TOP
R74       2429.00     6774.00       0.000    TOP
R75       2389.36     6651.69     180.000    TOP
R76       2600.00     6430.00     270.000    TOP
R77       2372.00     6591.00      90.000    TOP
R78       2585.00     6775.00     180.000    TOP
R79       2668.00     6693.00     180.000    TOP
R80       2600.19     6622.09      90.000    TOP
R81       2584.31     7061.90       0.000    TOP
R82       2626.45     7062.01     180.000    TOP
R83       1812.44     4698.67     270.000    TOP
R84       1059.20     4836.98     180.000    TOP
R85       1102.20     4836.98       0.000    TOP
R86       1812.44     4597.67     270.000    TOP
R87       1991.00     5028.00      90.000    TOP
R88       1884.00     5046.00     180.000    TOP
R89       1760.41     4957.10     270.000    TOP
R90       1833.20     4797.98     180.000    TOP
R91       1789.20     4797.98     180.000    TOP
R92       3399.00     6961.00     270.000    BOT
R93       3456.54     6983.15       0.000    BOT
R95       3067.51     5353.56     270.000    TOP
R96       3359.62     7038.96       0.000    BOT
R97       3475.00     7080.00       0.000    BOT
R98       3143.33     5353.57      90.000    TOP
R99       3280.16     5438.16     270.000    TOP
R100      3774.57     6952.03     270.000    BOT
R101      3755.00     7060.00       0.000    BOT
R102      2890.50     5370.00     180.000    TOP
R105      3341.65     5396.09     270.000    TOP
R123      3879.00     6779.00     270.000    TOP
R124      3903.55     6846.44     270.000    TOP
R127      3107.00     5609.00     180.000    BOT
R128      3144.00     5730.00     270.000    BOT
R129      3011.76     5576.11      90.000    TOP
R130      3009.00     5642.00      90.000    TOP
R131      2934.00     5656.00      90.000    TOP
R132      2958.00     5697.00      90.000    TOP
R133      3452.87     5392.59     180.000    TOP
R134      3409.42     5302.26       0.000    TOP
R135      3436.78     5170.86      90.000    TOP
R136      3470.00     5451.00      90.000    TOP
R137      3500.00     5307.00       0.000    TOP
R138      3500.00     5227.00       0.000    TOP
R139      3856.00     5342.00       0.000    TOP
R140      1869.00     5344.00     180.000    BOT
R141      1741.02     5740.58     270.000    BOT
R142      1910.00     5343.00       0.000    BOT
R143      1737.87     5871.47      90.000    BOT
R144       866.59     5157.77     180.000    TOP
R145      1565.01     5625.67     180.000    BOT
R146      2169.00     5139.66       0.000    TOP
R147      2126.00     5187.00       0.000    TOP
R148      2035.00     5186.00       0.000    TOP
R149      1995.00     5187.00       0.000    TOP
R151      2400.00     5626.00      90.000    BOT
R152      1873.00     5047.00       0.000    BOT
R153      2400.00     5667.00      90.000    BOT
R154      1786.00     5341.00     180.000    BOT
R155      2422.96     5606.98      90.000    TOP
R156      1826.00     5343.00     180.000    BOT
R157      2422.96     5647.98      90.000    TOP
R158      1747.15     5187.20     180.000    TOP
R159      2668.00     5734.00     180.000    BOT
R160      2413.18     5688.21     270.000    TOP
R161      2668.16     5628.37       0.000    BOT
R162      2413.18     5728.21     270.000    TOP
R163      2403.00     5751.00      90.000    BOT
R164      2416.00     5811.00     270.000    TOP
R165      2403.00     5710.00      90.000    BOT
R166      2417.00     5769.00     270.000    TOP
R167      2027.00     5344.00       0.000    BOT
R168      1932.85     6228.00       0.000    TOP
R169      2281.02     5311.42       0.000    BOT
R170      1891.85     6228.00       0.000    TOP
R171      1850.85     6228.00       0.000    TOP
R172      1810.85     6228.00       0.000    TOP
R173      1770.00     6217.00       0.000    TOP
R174      1729.00     6217.00       0.000    TOP
R175      2261.09     5580.53     270.000    BOT
R176      2412.70     5566.58     270.000    TOP
R177      1870.00     5187.00     180.000    TOP
R178      1911.00     5182.00     180.000    TOP
R179      1852.76     6345.68     180.000    TOP
R180      1811.46     6353.08     180.000    TOP
R181      2497.66     5671.08      90.000    TOP
R182      2494.00     5735.00      90.000    TOP
R183      1831.00     5048.00       0.000    BOT
R184      1792.00     5267.00       0.000    BOT
R185      2402.00     5585.00      90.000    BOT
R186      2565.74     5520.61      90.000    TOP
R187      1771.00     6353.00     180.000    TOP
R188      1730.00     6353.00     180.000    TOP
R189      2494.00     5857.00      90.000    TOP
R190      2491.50     5783.00      90.000    TOP
R191      1991.90     6117.00     270.000    BOT
R192      2037.40     6247.80      90.000    BOT
R193      2709.47     5747.04     180.000    BOT
R194      2708.36     5628.19       0.000    BOT
R195      2461.45     5596.18       0.000    BOT
R196      2480.00     5659.00      90.000    BOT
R197      2263.16     6589.67      90.000    TOP
R198      2496.96     5567.61      90.000    TOP
R199      2497.77     5630.68      90.000    TOP
R200      1841.67     5046.84       0.000    TOP
R201      2480.32     5790.67      90.000    BOT
R202      2480.17     5699.57      90.000    BOT
R203      1934.76     6345.68     180.000    TOP
R204      1893.76     6345.68     180.000    TOP
R205       802.24     5583.98     270.000    BOT
R206       802.25     5543.63     270.000    BOT
R207       349.58     5382.54      90.000    TOP
R208       425.06     5382.49      90.000    TOP
R209       524.56     5717.95      90.000    BOT
R210       568.00     5758.50      90.000    BOT
R211       401.00     5609.00      90.000    BOT
R212       476.85     5608.79      90.000    BOT
R213       866.73     5083.00     180.000    TOP
R214       920.00     5157.00     180.000    TOP
R215       753.73     5081.79     180.000    TOP
R216       754.05     5157.77     180.000    TOP
R217       348.00     5495.00      90.000    TOP
R218       423.00     5495.00      90.000    TOP
R219      1086.00     5722.50       0.000    TOP
R220       699.00     5083.00     180.000    TOP
R221       697.78     5157.77     180.000    TOP
R222       997.76     5601.66     270.000    BOT
R223       997.44     5552.40     270.000    BOT
R224       424.06     5326.22      90.000    TOP
R225       810.68     5081.66     180.000    TOP
R226       810.32     5157.77     180.000    TOP
R227       349.87     5551.53      90.000    TOP
R228       424.87     5551.53      90.000    TOP
R229       350.58     5438.81      90.000    TOP
R230       425.06     5438.76      90.000    TOP
R231      1011.00     5136.00     180.000    TOP
R232      1011.13     5210.77     180.000    TOP
R233       402.03     5495.08      90.000    BOT
R234       476.85     5495.26      90.000    BOT
R235       753.73     5081.79     180.000    BOT
R236       754.05     5157.77     180.000    BOT
R237       401.32     5212.71      90.000    BOT
R238       476.06     5212.69      90.000    BOT
R239       349.65     5326.38     270.000    TOP
R240       698.78     5080.77     180.000    BOT
R241       697.78     5157.77     180.000    BOT
R242       401.75     5269.95      90.000    BOT
R243       476.06     5269.95      90.000    BOT
R244       979.00     5083.00     180.000    BOT
R245       979.13     5157.77     180.000    BOT
R246       401.58     5438.81      90.000    BOT
R247       476.06     5438.76      90.000    BOT
R248       922.73     5083.00     180.000    BOT
R249       922.86     5157.77     180.000    BOT
R250       400.58     5382.54      90.000    BOT
R251       476.06     5382.49      90.000    BOT
R252       810.68     5081.66     180.000    BOT
R253       810.32     5157.77     180.000    BOT
R254       401.85     5551.53      90.000    BOT
R255       476.85     5551.53      90.000    BOT
R256       401.65     5326.38      90.000    BOT
R257       476.06     5326.22      90.000    BOT
R258       642.51     5081.77     180.000    BOT
R259       641.51     5157.77     180.000    BOT
R260       866.73     5083.00     180.000    BOT
R261       866.59     5157.77     180.000    BOT
R262      1707.00     5187.00     180.000    TOP
R263      1666.00     5187.00     180.000    TOP
R264      1788.69     5186.93     180.000    TOP
R265      1828.74     5186.91     180.000    TOP
R266      2697.00     4703.00     270.000    TOP
R267      2701.00     4903.00     270.000    TOP
R268      2697.00     4582.00     270.000    TOP
R269      2104.00     4953.00      90.000    TOP
R270      1708.00     5048.00       0.000    BOT
R271      2412.70     5525.58      90.000    TOP
R272      2402.00     5544.00      90.000    BOT
R273      2402.00     5504.00      90.000    BOT
R275      3653.00     5406.00     270.000    BOT
R276      1463.00     4978.00       0.000    BOT
R277      1454.00     5343.00     180.000    BOT
R278      2256.00     5170.80       0.000    TOP
R279      1987.50     6076.00      90.000    BOT
R280      1386.00     5297.00      90.000    TOP
R281      1996.16     6205.90     270.000    BOT
R282      1513.15     4769.38      90.000    BOT
R283      1287.00     5346.00      90.000    TOP
R284      1670.00     5188.00     180.000    BOT
R285      1513.85     4685.62     270.000    BOT
R286      1918.69     5047.89     180.000    BOT
R287      1930.00     5047.00     180.000    TOP
R288      2302.62     5169.80     180.000    TOP
R289      2343.48     5169.14     180.000    TOP
R290      2386.48     5169.14     180.000    TOP
R291      1986.00     5345.00     180.000    BOT
R292      1790.00     5048.00       0.000    BOT
R293      1756.00     5170.00     270.000    BOT
R294      1998.92     5013.22     180.000    BOT
R295      2192.00     5348.00     180.000    BOT
R297      2025.60     6257.66     180.000    TOP
R298      1973.15     6240.97     180.000    TOP
R299      1519.00     6356.00       0.000    TOP
R300      1478.00     6356.00       0.000    TOP
R301      1610.00     6460.00       0.000    TOP
R302      1551.00     6484.00      90.000    TOP
R303      2475.00     6062.60     270.000    BOT
R304      2398.50     6108.60     270.000    BOT
R305      2893.00     6170.00     270.000    TOP
R306      2693.00     6055.00     270.000    TOP
R307      3002.00     5919.00     180.000    TOP
R308      1420.00     5138.00     180.000    TOP
R309      1648.00     6353.00       0.000    TOP
R310      1929.11     6349.48       0.000    BOT
R311      1711.93     6353.03     270.000    BOT
R312      1421.00     5216.00       0.000    TOP
R313      1689.00     6353.00       0.000    TOP
R314      1550.00     4981.00       0.000    BOT
R315      2050.20     6104.40       0.000    BOT
R316      1500.67     6124.43     180.000    BOT
R317      1494.00     6245.00       0.000    TOP
R318      1500.54     5888.02     270.000    BOT
R319      1329.62     6033.11     270.000    TOP
R320      1337.18     6176.77     270.000    TOP
R321      1497.57     6025.62     270.000    BOT
R322      1344.53     6097.77     270.000    TOP
R323      1971.91     6348.88       0.000    BOT
R324      1836.00     6353.00      90.000    BOT
R325      1667.00     5048.00       0.000    BOT
R326      1622.00     6067.60      90.000    BOT
R327      1650.00     6460.00     180.000    TOP
R328      1537.00     6245.00     180.000    TOP
R329      2951.00     5737.00      90.000    TOP
R330      1493.00     6467.00     180.000    TOP
R331      1217.03     6098.18      90.000    TOP
R332      2709.00     6723.00     180.000    TOP
R333      1329.50     5992.50     270.000    TOP
R334      2676.12     5838.09     270.000    BOT
R335      2441.56     6154.87       0.000    TOP
R336      1287.92     6028.54      90.000    BOT
R337      1512.65     4810.57     270.000    BOT
R338      2420.00     5889.00      90.000    TOP
R339      1514.15     4727.38      90.000    BOT
R340      2416.00     6010.00      90.000    TOP
R341      1514.00     4602.00     270.000    BOT
R342      1961.15     4759.38      90.000    BOT
R343      2451.00     5312.40     270.000    BOT
R344      1960.15     4718.38      90.000    BOT
R345      2156.58     4852.33       0.000    BOT
R346       935.31     4946.41     180.000    TOP
R347      1514.15     4643.38      90.000    BOT
R348      1505.00     4980.80       0.000    BOT
R349      8162.00     3146.00      90.000    BOT
R350      1602.30     5101.40     270.000    BOT
R351      1387.24     5383.35      90.000    TOP
R352      2439.93     5328.02     270.000    TOP
R353      2151.00     5343.00     180.000    BOT
R354      2413.10     5371.39      90.000    TOP
R355      2109.00     5343.00       0.000    BOT
R356      2498.42     7090.10       0.000    TOP
R357      2009.10     5614.90     180.000    BOT
R358      2284.00     5660.50     180.000    BOT
R359      2260.00     5859.00     270.000    BOT
R360      2260.75     5768.16     270.000    BOT
R361      2257.00     5719.00     270.000    BOT
R362      1628.00     4926.00     180.000    BOT
R363      1968.90     5656.00     180.000    BOT
R364      1668.61     4926.20       0.000    BOT
R365      2258.48     5816.66      90.000    BOT
R366      1984.60     5993.40     270.000    BOT
R367      1884.00     6457.00     180.000    TOP
R368      1859.50     6073.60     270.000    BOT
R369      1287.00     5303.00      90.000    TOP
R370      1627.00     5188.00     180.000    BOT
R371      1749.00     5048.00     180.000    BOT
R372      1745.00     5341.00     180.000    BOT
R373      1653.00     5277.00      90.000    BOT
R374      1712.00     5241.00     180.000    BOT
R375      1593.00     5280.00     180.000    BOT
R376      1607.27     5185.22     180.000    TOP
R377      1501.12     5147.98     180.000    TOP
R378      1567.21     5184.92     180.000    TOP
R379      1461.12     5147.98     180.000    TOP
R380      2685.00     5721.00     270.000    TOP
R381      2734.90     5861.02       0.000    BOT
R382      2522.72     6148.81       0.000    TOP
R383      2249.00     5972.00     270.000    BOT
R384      2381.00     5847.00     180.000    BOT
R385      2646.00     5673.00     270.000    TOP
R386      2676.09     5878.13      90.000    BOT
R387      2482.15     6148.87     180.000    TOP
R388      2249.00     5932.00     270.000    BOT
R389      2421.00     5847.00     180.000    BOT
R390      2259.00     6254.00       0.000    TOP
R391      2299.00     6267.00       0.000    TOP
R392      2365.00     6332.00      90.000    TOP
R393      2480.65     5942.50     270.000    BOT
R394      2370.62     6064.22     270.000    BOT
R395      2219.00     6254.00       0.000    TOP
R396      2340.00     6245.00       0.000    TOP
R397      2380.00     6245.00       0.000    TOP
R398      2420.00     5925.00     180.000    BOT
R399      2371.10     6021.60     270.000    BOT
R400      1975.55     6349.57       0.000    TOP
R401      2134.00     6422.00     270.000    BOT
R402      2234.00     6397.00       0.000    TOP
R403      2345.00     6423.00     270.000    BOT
R404      2135.00     6345.00      90.000    BOT
R405      2192.00     6423.00     180.000    TOP
R406      2345.00     6379.00     270.000    BOT
R407      2346.00     6376.00     270.000    TOP
R408      2054.00     6412.70      90.000    BOT
R409      2008.50     6447.00       0.000    TOP
R410      2313.00     6438.00     180.000    TOP
R411      2054.90     6372.50     270.000    BOT
R412      2117.06     6396.92     180.000    TOP
R413      2237.92     6420.06     270.000    BOT
R414      2049.00     6531.00      90.000    BOT
R415      2238.08     6378.94      90.000    BOT
R416      2128.08     6532.94      90.000    BOT
R417      3553.00     6834.00      90.000    BOT
R418      3458.00     6875.00      90.000    BOT
R419      3642.00     6642.00     270.000    BOT
R420      3495.61     5078.31      90.000    TOP
R421      3495.00     5119.00     270.000    TOP
R422      3459.00     5798.00       0.000    TOP
R423      3915.49     5619.00     180.000    TOP
R424      3458.17     5758.41     270.000    BOT
R425      3654.00     5744.00       0.000    BOT
R426      3880.00     5765.00     270.000    TOP
R427      3880.00     5725.00     270.000    TOP
R428      3880.00     5685.00      90.000    TOP
R429      3452.44     5855.60     180.000    BOT
R430      3695.00     5744.00     180.000    BOT
R431      4632.00      574.00       0.000    TOP
R432      4842.25      588.50      90.000    TOP
R433      4914.79      304.48     270.000    BOT
R434      4841.00      679.73      90.000    TOP
R435      4915.00      340.00      90.000    TOP
R436      4557.00      336.00      90.000    BOT
R437      4915.00      385.00     270.000    BOT
R438      4915.00      300.00     270.000    TOP
R439      4883.00      491.00      90.000    TOP
R440      4682.00      643.00       0.000    TOP
R441      4725.00      642.00       0.000    TOP
R442      5272.00      536.00     270.000    TOP
R443      5272.00      494.00     270.000    TOP
R444      5403.00      516.00     180.000    TOP
R445      4906.53      624.37       0.000    BOT
R446      5090.00      650.00     270.000    BOT
R447      5004.11      535.65       0.000    BOT
R448      5122.90      559.73       0.000    BOT
R449      4914.94      344.55      90.000    BOT
R450      5166.57      254.44     270.000    TOP
R451      3152.90     6801.70     180.000    BOT
R452      3182.00     6581.00     270.000    BOT
R453      4447.54      441.01       0.000    TOP
R454      4358.85      380.57     270.000    TOP
R455      5073.22      251.93       0.000    TOP
R456      4442.85      219.57     270.000    TOP
R457      4447.22      517.15     180.000    TOP
R458      4387.81      569.47     270.000    TOP
R459      4443.85      304.57     270.000    TOP
R460      4443.85      261.57     270.000    TOP
R461      4397.00      378.00      90.000    BOT
R462      4443.16      381.47     270.000    TOP
R463      7178.76     5983.29     270.000    TOP
R464      6972.00     5451.00     180.000    BOT
R465      7178.76     5940.29      90.000    TOP
R466      7065.06     6002.99     180.000    BOT
R467      7038.00     6032.00       0.000    TOP
R468      7095.00     6145.00      90.000    TOP
R469      6794.76     5795.71      90.000    TOP
R470      7135.75     5544.77       0.000    TOP
R471      7078.26     6031.79     180.000    TOP
R472      7219.00     5606.00     270.000    TOP
R473      7310.76     5986.29       0.000    TOP
R474      7316.76     5894.29     180.000    TOP
R475      7219.00     5646.00     270.000    TOP
R476      7048.38     5536.02      90.000    TOP
R477      7203.00     5691.00      90.000    TOP
R478      7280.00     5819.50       0.000    TOP
R479      2376.99     7379.47     270.000    TOP
R480      2376.99     7283.47     270.000    TOP
R481      2376.99     7187.47     270.000    TOP
R482      1558.49     6974.15     180.000    TOP
R483       997.00     7122.00     270.000    BOT
R484      1497.00     7192.00     180.000    BOT
R485      1643.49     6971.15       0.000    TOP
R486      1517.49     6974.15       0.000    TOP
R487      1583.49     7052.15     180.000    TOP
R488      1664.00     7065.00       0.000    TOP
R489      1563.49     6877.15     270.000    TOP
R490      1326.51     7362.15       0.000    TOP
R491      1543.00     7052.15       0.000    TOP
R492      1115.99     7014.65     270.000    TOP
R493      1133.49     6953.47     180.000    TOP
R494      1174.49     6953.47     180.000    TOP
R495      1112.00     7116.00       0.000    TOP
R496      1468.49     6837.15      90.000    TOP
R497      1215.49     6930.47     180.000    TOP
R498      1568.49     7112.15      90.000    TOP
R499      1393.49     6877.15     270.000    TOP
R500      3706.82     1945.74       0.000    TOP
R501      3686.72     2452.84      90.000    TOP
R502      3624.84     1984.19     180.000    TOP
R503      3439.29     1936.78      90.000    TOP
R504      3093.00     6793.00     180.000    TOP
R505      2930.18     6841.53     270.000    TOP
R506      2930.82     6919.47      90.000    TOP
R507      2917.00     7319.00       0.000    TOP
R508      2876.20     7319.20       0.000    TOP
R509      2737.20     7189.20      90.000    TOP
R510      2689.00     7235.00     270.000    TOP
R511      6484.00     5451.00      90.000    TOP
R512      6592.00     5437.00     180.000    TOP
R513      6326.28     5563.27       0.000    TOP
R514      6426.60     5650.43       0.000    TOP
R515      6412.00     5537.00     270.000    TOP
R516      6411.60     5495.43      90.000    TOP
R517      6401.60     5235.43     180.000    TOP
R518      6235.42     5654.52     180.000    TOP
R519      6481.00     5041.00      90.000    TOP
R520      6066.60     5285.43      90.000    TOP
R521      6194.00     5655.00     180.000    TOP
R522      6031.64     5425.03     180.000    TOP
R523      6967.00     4716.00     180.000    TOP
R524      6977.00     5040.00      90.000    TOP
R525      6728.50     4706.84      90.000    TOP
R526      6890.00     5015.00       0.000    TOP
R527      6742.00     5039.00      90.000    TOP
R528      6639.00     4432.00     270.000    TOP
R529       777.66     6337.46     180.000    TOP
R530       631.54     6399.50     270.000    TOP
R531       630.46     6478.50      90.000    TOP
R532       806.00     6872.00       0.000    TOP
R533       761.00     6920.00       0.000    TOP
R534       461.00     6732.84     180.000    TOP
R535       404.33     6799.46     270.000    TOP
R536      3119.36     6052.96     180.000    TOP
R537      3037.00     6163.84     270.000    TOP
R538      3037.48     6204.77      90.000    TOP
R539      3051.00     6598.00       0.000    TOP
R540      2898.00     6622.00       0.000    TOP
R541      2836.60     6479.50      90.000    TOP
R542      2836.60     6521.00      90.000    TOP
R543      8397.00     4695.00     270.000    TOP
R544      8076.00     4735.00     270.000    TOP
R545      8076.34     4809.00      90.000    TOP
R546      8052.49     5215.77       0.000    TOP
R547      7959.22     5246.08       0.000    TOP
R548      7869.84     5056.00      90.000    TOP
R549      7842.54     5143.50      90.000    TOP
R550      7790.00     5185.00      90.000    TOP
R551      7694.34     5185.00     270.000    TOP
R552      7770.84     5247.50     180.000    TOP
R553      7904.00     4181.00       0.000    TOP
R554      7592.00     5025.00       0.000    TOP
R555      7770.00     4908.00     180.000    TOP
R556      7530.99     5247.66       0.000    TOP
R557      7693.19     4887.99      90.000    TOP
R558      7488.99     5246.66       0.000    TOP
R559      7401.00     4897.84     180.000    BOT
R560      7356.00     4897.84     180.000    BOT
R561      7446.00     4897.84     180.000    BOT
R562      7506.00     4906.00       0.000    BOT
R563      7514.00     5025.00     180.000    TOP
R564      7418.00     5013.00     270.000    TOP
R565      7772.00     4985.00       0.000    TOP
R566      7455.00     5086.00      90.000    TOP
R567      7083.00     4510.00       0.000    BOT
R568      6965.27     4590.06     180.000    TOP
R569      8215.00     3225.00      90.000    TOP
R570      8135.00     3225.00     270.000    TOP
R571      8829.13     2304.98     180.000    TOP
R572      6833.42     2445.47     270.000    TOP
R573      7093.52     2619.99     270.000    BOT
R574      6966.00     2494.00     270.000    TOP
R575      7106.79     2579.64      90.000    BOT
R576      6872.47     2734.30      90.000    TOP
R577      6873.00     2651.00      90.000    BOT
R578      6869.00     2595.00      90.000    TOP
R579      6956.00     2368.50      90.000    TOP
R580      6872.47     2775.30      90.000    TOP
R581      6868.00     2554.00      90.000    TOP
R582      6831.47     2404.30      90.000    TOP
R583      6873.00     2692.00      90.000    BOT
R584      7120.73     2538.83      90.000    BOT
R585      6872.47     2692.30      90.000    TOP
R586      6871.00     2859.00      90.000    TOP
R587      6872.47     2817.30      90.000    TOP
R588      8230.00     2402.00     270.000    BOT
R589      8218.00     2482.00     270.000    BOT
R590      8061.00     2242.00     180.000    BOT
R591      8021.00     2242.00     180.000    BOT
R592      8181.00     2242.00     180.000    BOT
R593      8141.00     2242.00     180.000    BOT
R594      8229.68     2359.64     270.000    BOT
R595      8101.00     2242.00     180.000    BOT
R596      3141.81     5877.50       0.000    TOP
R597      6320.22     3795.91     270.000    TOP
R598      8139.28     2536.64      90.000    BOT
R599      2019.00     4956.00     270.000    TOP
R600      8570.00     4051.00       0.000    TOP
R601      2750.67     5574.80     270.000    TOP
R602      8162.72     3936.39     270.000    TOP
R603      8575.69     3866.33     180.000    TOP
R604      8672.50     4034.00      90.000    TOP
R605      8610.00     4051.00     180.000    TOP
R606      8165.67     3989.68     270.000    TOP
R607      2068.00     5342.80       0.000    BOT
R608      8186.88     4049.55       0.000    TOP
R609      8093.49      683.36     180.000    TOP
R610      2104.00     4993.00     270.000    TOP
R611      1556.58     5176.77     270.000    BOT
R612      1556.88     5221.34     270.000    BOT
R613      1861.11     5184.81     180.000    BOT
R614      8134.49      683.36     180.000    TOP
R615      8162.00     3104.00     270.000    BOT
R616      6149.86     3672.71     270.000    BOT
R617      3007.32     5781.08      90.000    TOP
R618      7685.29     1976.54     180.000    BOT
R619      6845.00     3070.00      90.000    TOP
R620      7322.30     3095.69       0.000    BOT
R621      7180.00     3480.00       0.000    TOP
R622      8855.68     3203.41       0.000    TOP
R623      6464.69     4191.86       0.000    TOP
R624      6983.00     2448.00      90.000    TOP
R625      8127.00     2578.00     270.000    BOT
R626      6371.47     3984.97       0.000    TOP
R627      7225.00     3480.00       0.000    TOP
R628      7060.00     3265.00       0.000    TOP
R629      8056.00     1901.00     180.000    TOP
R630      8288.00     2376.00       0.000    BOT
R631      8006.00     1901.00     180.000    TOP
R632      7956.00     1901.00     180.000    TOP
R633      7856.00     1901.00     180.000    TOP
R634      7906.00     1901.00     180.000    TOP
R635      8106.00     1901.00     180.000    TOP
R636      7755.00     1900.00     180.000    TOP
R637      8230.00     2442.00     270.000    BOT
R638      6060.08     3734.37      90.000    TOP
R639      5952.00     3733.00      90.000    TOP
R640      7499.00     1904.00     180.000    TOP
R641      7272.00     3578.00       0.000    TOP
R642      7135.00     3579.00       0.000    TOP
R643      7383.65     3577.35       0.000    TOP
R644      7140.90     3265.40       0.000    TOP
R645      7622.00     1905.00     180.000    TOP
R646      7457.00     1907.00     180.000    TOP
R647      6873.00     2651.00      90.000    TOP
R648      7846.90     2498.80      90.000    BOT
R649      6837.00     2491.00      90.000    TOP
R650      7268.30     2879.30      90.000    BOT
R651      3106.50     6580.50     270.000    BOT
R652      7540.00     1905.00       0.000    TOP
R653      7270.00     3480.00     180.000    TOP
R654      7117.00     3470.00     180.000    TOP
R655      7384.65     3479.35     180.000    TOP
R656      7100.60     3265.60     180.000    TOP
R657      7413.00     1905.00       0.000    TOP
R658      7581.00     1901.00       0.000    TOP
R659      7314.00     3577.00     180.000    TOP
R660      7340.28     1806.46     180.000    TOP
R661      7166.50     1793.00     180.000    TOP
R662      6982.20     1977.40      90.000    TOP
R663      6956.00     2284.00      90.000    TOP
R664      6956.00     2324.00      90.000    TOP
R665      7370.00     1907.00     180.000    TOP
R666      7474.00     2085.00     270.000    BOT
R667      7271.50     1895.50       0.000    TOP
R668      7221.50     1895.50       0.000    TOP
R669      7256.78     1786.92       0.000    TOP
R670      7166.50     1895.50       0.000    TOP
R671      7056.50     1895.50       0.000    TOP
R672      7111.50     1895.50       0.000    TOP
R673      7111.50     1793.00       0.000    TOP
R674      6978.00     2076.00     270.000    TOP
R675      7320.00     1907.00     180.000    TOP
R676      6566.65     3001.66       0.000    BOT
R677      6524.65     3002.66       0.000    BOT
R678      6702.00     2016.00     180.000    BOT
R679      7630.00     1808.00      90.000    BOT
R680      7917.73     1823.18      90.000    BOT
R681      8061.92     1822.09      90.000    BOT
R682      6717.00     3074.00      90.000    BOT
R683      7779.00     1822.00      90.000    BOT
R684      8340.00     3530.00     270.000    BOT
R685      8157.26     3655.56       0.000    BOT
R686      7065.80     3188.40       0.000    BOT
R687      8802.23     3876.17       0.000    TOP
R688      3519.00     5306.00     180.000    BOT
R689      6390.67     3602.91       0.000    TOP
R690      6346.61     3690.56     180.000    TOP
R691      6208.22     3741.64     180.000    TOP
R692      6132.23     3742.27       0.000    TOP
R693      6232.39     3391.79     180.000    TOP
R694      6085.00     3377.00     180.000    TOP
R695      7844.00     1010.00       0.000    TOP
R696      7777.00      759.00     180.000    TOP
R697      1712.02     6298.26      90.000    BOT
R698      1279.00     6497.00       0.000    TOP
R699      1361.00     6497.00     180.000    TOP
R700      1244.00     6364.00      90.000    TOP
R701      1246.97     6019.23      90.000    TOP
R702      2135.20     4911.00      90.000    BOT
R703      1239.00     6497.00       0.000    TOP
R704      3687.72     2406.84      90.000    TOP
R705      1321.00     6497.00     180.000    TOP
R706      1244.00     6323.00      90.000    TOP
R707      1407.00     6518.00       0.000    TOP
R708      2427.00     5169.20     180.000    TOP
R709      5075.49      344.52      90.000    TOP
R710      5075.49      422.52     270.000    TOP
R711      4915.00      260.00     270.000    TOP
R712      4915.00      220.00     270.000    TOP
R713      7163.45     6100.90     180.000    TOP
R714      1453.00     6245.00       0.000    TOP
R715      3495.00     5036.00     270.000    TOP
R716      1367.02     4908.61     180.000    BOT
R717      3043.00     5919.00     180.000    TOP
R718      3330.00     5120.00      90.000    BOT
R719      3685.42     2249.34      90.000    TOP
R720      3190.00     5529.00     270.000    BOT
R721      3577.96     5452.20     270.000    BOT
R722      3603.00     5601.00       0.000    BOT
R723      3365.00     6718.00     180.000    TOP
R724      3874.00     6718.00     270.000    TOP
R725      3544.40     4875.30       0.000    TOP
R726      3280.00     6716.00       0.000    TOP
R727      7023.90     4905.60     180.000    TOP
R728      3491.82     3795.74     180.000    BOT
R729      6978.50     2035.60      90.000    TOP
R730      7841.61     1251.15       0.000    TOP
R731      2579.20     5328.70     270.000    TOP
R732      1196.30     4995.50     270.000    BOT
R733      7697.55      397.35      90.000    TOP
R734      1274.70     4993.50      90.000    BOT
R735      5610.00      820.00     270.000    TOP
R736      3869.25     6933.71     270.000    TOP
R737      5820.90      516.80       0.000    TOP
R738      2931.50     5370.00     180.000    TOP
R739      2419.00     5390.00      90.000    BOT
R740      1448.00     6518.00       0.000    TOP
R741      4564.00      561.00       0.000    BOT
R742      4816.00      629.00     270.000    BOT
R743      4816.00      589.00     270.000    BOT
R744      4582.00      619.00      90.000    BOT
R745      8240.24      420.00     270.000    TOP
R746      8413.00      595.80     180.000    TOP
R747      6340.00     1925.00     180.000    BOT
R748      6295.00     1925.00       0.000    BOT
R763      2760.00     5750.00      90.000    TOP
R764      2696.00     4745.00      90.000    TOP
R765      1812.20     4739.98      90.000    TOP
R766      6977.03     2117.43      90.000    TOP
R767      7309.00     1930.00     180.000    BOT
R768      1110.00     5970.00     270.000    TOP
R769      1110.00     6010.00     270.000    TOP
R770      1110.00     6090.00     270.000    TOP
R771      1110.00     6050.00     270.000    TOP
R772      1110.00     6130.00     270.000    TOP
R773      1115.00     6210.00     270.000    TOP
R774      2613.96     6300.71     270.000    TOP
R775      2615.73     6343.43      90.000    TOP
R776      2085.16     6552.01       0.000    TOP
R777      2043.57     6551.86     180.000    TOP
R778      1966.48     6553.21       0.000    TOP
R779      1917.46     6553.42     180.000    TOP
R780      2771.50     6027.00     270.000    TOP
R781      1789.20     4873.78       0.000    TOP
R782      1278.00     6164.00     180.000    BOT
R783      1407.02     4908.61       0.000    BOT
R784      2325.00     5275.00     180.000    BOT
R785      2439.00     5431.00     270.000    BOT
R786      1110.00     6170.00     270.000    TOP
R787      1832.77     4873.78       0.000    TOP
R788      1102.20     4913.78       0.000    TOP
R789      1059.20     4914.18       0.000    TOP
R795      3688.00     6719.00      90.000    BOT
R796      3563.30     4815.70      90.000    TOP
R797      3635.53     4779.62     180.000    TOP
R800      7515.00      512.30     180.000    TOP
R801      5638.70      524.03     180.000    TOP
R817      7980.24      420.00     270.000    TOP
R833      6320.22     3753.05      90.000    TOP
R7909     7427.00     4614.80       0.000    TOP
RST1       472.44      246.06       0.000    TOP
SKT1      1447.60     4777.99     270.000    TOP
SKT2      2398.00     4778.00     270.000    TOP
SX1       8905.00     2340.00      90.000    TOP
TP1       5200.00     1087.00       0.000    TOP
TP2       5199.00     1031.50       0.000    TOP
TP3       5330.80     1083.00       0.000    TOP
TP4       3599.29     6266.17      90.000    BOT
TP5       3685.00     5919.00     270.000    TOP
TP6       3843.65     6057.13      45.000    BOT
TP9       2028.00     5099.00       0.000    TOP
TP10      2080.00     5205.00       0.000    TOP
TP11      2171.00     5203.00       0.000    TOP
TP12      2081.00     5152.00       0.000    TOP
TP13      1741.00     6289.00       0.000    TOP
TP14      1688.00     6284.00       0.000    TOP
TP15      2321.67     5549.62       0.000    BOT
TP16      2499.98     5502.19       0.000    TOP
TP17      1536.24     5436.94       0.000    BOT
TP18      1617.50     5350.00       0.000    BOT
TP19      1932.38     4659.85       0.000    BOT
TP20      1905.00     5471.00       0.000    BOT
TP21      1781.00     5487.00       0.000    BOT
TP27      1705.45     5397.79       0.000    BOT
TP28      1752.00     5550.00       0.000    BOT
TP29      1650.30     5391.70       0.000    BOT
TP50      2356.00     6118.00       0.000    TOP
TP51      2069.00     5771.00     270.000    BOT
TP52      2078.20     5708.60       0.000    BOT
TP53      2261.68     6189.52      90.000    TOP
TP54      2196.27     5625.52       0.000    BOT
TP55      2468.00     5419.00       0.000    TOP
TP57      1405.00     6203.00       0.000    TOP
TP62      1563.91     5909.72       0.000    BOT
TP63      1588.62     6141.07       0.000    BOT
TP64      1553.43     6091.68       0.000    BOT
TP65      1556.60     5991.40     270.000    BOT
TP66      1702.00     6036.00     270.000    BOT
TP68      2208.32     5517.76     270.000    BOT
TP69      2318.92     5468.71     270.000    BOT
TP70      2219.56     5445.87     270.000    BOT
TP71      2411.00     5416.00       0.000    TOP
TP72      1974.00     5490.00       0.000    BOT
TP73      2196.91     5571.04       0.000    BOT
TP74      2355.62     5410.96      90.000    TOP
TP75      2409.00     5473.00       0.000    TOP
TP76      2259.32     5482.76       0.000    BOT
TP77      2355.00     5482.00       0.000    TOP
TP78      2023.80     5679.70       0.000    BOT
TP79      2231.92     5670.00       0.000    BOT
TP80      2196.88     5877.96       0.000    BOT
TP81      2196.48     5768.01       0.000    BOT
TP82      2194.85     5823.48       0.000    BOT
TP83      2188.01     5710.96      90.000    BOT
TP84      1594.00     4983.00       0.000    BOT
TP85      7205.30     3122.10       0.000    BOT
TP86      7336.96     3009.91       0.000    BOT
TP87      7411.00     3074.00       0.000    BOT
TP88      7096.00     2994.00       0.000    BOT
TP89      7391.00     3021.26       0.000    BOT
TP90      6960.00     3111.00       0.000    TOP
TP91      7369.52     3113.91       0.000    BOT
TP92      7438.00     2786.00       0.000    BOT
TP93      6990.00     2901.00       0.000    TOP
TP94      7186.00     3043.00     270.000    BOT
TP95      7152.00     3000.00     270.000    BOT
TP96      6962.00     3017.00      90.000    TOP
TP97      7095.00     3084.00     270.000    BOT
TP98      7260.00     3220.00      90.000    TOP
TP99      7268.00     3131.13     270.000    BOT
TP100     6932.00     2795.50       0.000    BOT
TP101     7021.09     2979.03       0.000    BOT
TP102     7024.00     2867.00       0.000    BOT
TP103     7007.00     3051.00       0.000    BOT
TP104     7160.60     3093.20       0.000    BOT
TP105     7134.00     3168.00       0.000    TOP
TP106     7066.00     3038.00       0.000    BOT
TP107     6993.00     3069.00       0.000    TOP
TP108     6917.74     2889.67       0.000    BOT
TP109     7144.00     2686.00       0.000    BOT
TP110     7182.60     2949.51       0.000    BOT
TP111     8156.70     2428.90       0.000    BOT
TP112     7113.22     2941.99       0.000    BOT
TP113     8201.00     2526.00       0.000    BOT
TP114     7069.97     2831.55       0.000    BOT
TP115     8020.00     2325.00       0.000    BOT
TP116     7110.29     2791.14       0.000    BOT
TP117     7975.00     2260.00       0.000    BOT
TP118     7137.89     2841.35       0.000    BOT
TP119     6979.60     2924.00       0.000    BOT
TP120     8231.00     2254.00       0.000    BOT
TP121     6933.00     2970.00       0.000    TOP
TP122     8110.00     2343.00       0.000    BOT
TP123     7096.50     2494.00       0.000    BOT
TP124     8164.00     2359.00       0.000    BOT
TP125     7035.26     2759.39       0.000    BOT
TP126     8070.00     2305.00       0.000    BOT
TP127     7145.19     2751.14       0.000    BOT
TP128     7076.04     2720.70       0.000    BOT
TP129     8126.30     2492.29     270.000    BOT
TP130     7279.96     3036.99       0.000    BOT
TP131     7447.68     3008.64       0.000    BOT
TP133     6912.00     3063.00     180.000    TOP
TP134     7911.40     2477.40       0.000    BOT
TP135     7756.00     1967.00       0.000    TOP
TP136     8105.00     1967.00       0.000    TOP
TP137     7879.00     1967.00     270.000    TOP
TP138     7805.00     1905.00       0.000    TOP
TP139     7825.00     1968.00       0.000    TOP
TP140     7932.00     1967.00       0.000    TOP
TP141     7987.00     1967.00       0.000    TOP
TP142     8287.81     2310.61     270.000    BOT
TP143     7703.00     1967.00       0.000    TOP
TP144     8046.00     1967.00       0.000    TOP
TP145     7320.00     3414.00       0.000    TOP
TP146     7225.00     3410.00       0.000    TOP
TP147     7063.00     3199.00       0.000    TOP
TP148     7368.00     2783.00       0.000    BOT
TP149     7385.86     3407.30       0.000    TOP
TP150     7534.79     2079.14       0.000    BOT
TP151     7409.00     1967.50       0.000    TOP
TP152     7529.22     1967.89       0.000    TOP
TP153     7527.00     2141.00       0.000    BOT
TP154     7589.47     1967.61       0.000    TOP
TP155     8064.00     2573.00       0.000    BOT
TP156     7229.61     3009.82       0.000    BOT
TP157     7206.13     3215.39       0.000    TOP
TP158     7326.00     3469.00       0.000    TOP
TP159     7481.00     2813.00       0.000    BOT
TP160     6987.73     2785.97       0.000    BOT
TP161     7480.00     2880.00       0.000    BOT
TP162     7300.00     1968.00       0.000    TOP
TP163     7141.00     2388.00       0.000    BOT
TP164     7110.00     2328.00       0.000    BOT
TP165     7247.00     1968.00       0.000    TOP
TP166     7299.30     2119.40       0.000    BOT
TP167     7232.10     2098.50       0.000    BOT
TP168     7355.00     1968.00       0.000    TOP
TP169     7449.60     1974.30       0.000    BOT
TP170     6817.00     1556.00       0.000    TOP
TP171     6974.00     1555.00       0.000    TOP
TP172     6934.00     1517.00       0.000    TOP
TP173     6781.00     1515.00       0.000    TOP
TP174     6894.00     1555.00       0.000    TOP
TP175     7053.00     1551.00       0.000    TOP
TP176     6856.00     1514.00       0.000    TOP
TP177     7011.00     1516.00       0.000    TOP
TP178     5873.00     1514.00       0.000    TOP
TP179     6163.00     1514.00       0.000    TOP
TP180     5940.00     1515.00       0.000    TOP
TP181     6109.00     1515.00       0.000    TOP
TP182     6054.00     1514.00       0.000    TOP
TP183     6223.10     1574.70       0.000    TOP
TP184     6216.00     1516.00       0.000    TOP
TP185     6000.00     1515.00       0.000    TOP
TP186     1641.30     6255.50       0.000    TOP
TP187     1683.00     6219.00       0.000    TOP
TP188     1583.50     6290.40       0.000    TOP
TP189     1592.00     6232.40       0.000    TOP
TP190     1777.50     6032.50       0.000    BOT
TP191     1815.40     6444.50       0.000    TOP
TP192     2392.00     5270.00       0.000    BOT
TP193     2382.00     5246.00       0.000    TOP
TPM1      2137.01     6799.21       0.000    TOP
U1        7590.55     2562.99     180.000    TOP
U2        1877.95     5708.66     270.000    TOP
U5        2779.45     5493.94      90.000    TOP
U9        2485.31     6895.24       0.000    TOP
U10       2609.31     6893.24       0.000    TOP
U11       1447.60     4777.99      90.000    TOP
U12       3577.20     6920.00      90.000    BOT
U15       3578.20     7046.00      90.000    BOT
U16       3856.20     7087.00      90.000    BOT
U19       3106.52     5433.70     270.000    TOP
U26       3690.88     5291.81     270.000    TOP
U27       1734.72     4719.53      90.000    BOT
U28        788.76     5612.66       0.000    TOP
U29       2398.00     4778.00      90.000    TOP
U30       2776.00     5895.00     270.000    TOP
U31       2738.00     6896.00     180.000    TOP
U32       3374.00     6681.00      90.000    BOT
U33       3695.89     5098.69     270.000    TOP
U34       3668.39     5616.29     270.000    TOP
U35       4680.00      354.00      90.000    TOP
U36       3665.35     2146.73       0.000    TOP
U37       2166.00     5009.80       0.000    BOT
U38       8403.00     3963.00      90.000    TOP
U41       6015.00     3636.00     180.000    BOT
U42       6486.00     2491.00     180.000    BOT
U43       6297.34     3542.00       0.000    TOP
U44       6160.42     3544.16       0.000    TOP
U45       3114.70     5262.91      90.000    TOP
U46       3689.00     4903.00     180.000    TOP
U47       7864.20      503.12     180.000    TOP
U48       7653.00     1030.00     180.000    TOP
U49       7695.00      755.00       0.000    TOP
U50       5551.00      568.80       0.000    TOP
U51       5545.00      725.00      90.000    BOT
U52       5770.00      675.00      90.000    BOT
U95       7053.84     4676.80       0.000    TOP
U98       3560.00     1167.00      90.000    TOP
U99       3651.64     6126.20      90.000    TOP
U100      3661.00     5199.00     270.000    BOT
U101      3616.80     5324.00     270.000    BOT
U102      3240.00     5895.00      90.000    TOP
U103      3174.00     5120.00     270.000    BOT
U104      1236.00     4876.50     270.000    BOT
U105      3249.21     5682.67      90.000    TOP
U106      3650.00     7062.00      90.000    TOP
U107      3635.10     6839.80     270.000    TOP
USB1      3500.00      498.03       0.000    TOP
VIA1      3075.67     2793.42      90.000    TOP
VIA2      3042.67     2919.42      90.000    TOP
VIA3      3075.67     3045.42      90.000    TOP
VIA4      3042.67     3171.42      90.000    TOP
VIA5      3075.67     3298.42      90.000    TOP
VIA6      3042.67     3423.42      90.000    TOP
VIA7      3075.67     3549.42      90.000    TOP
VIA8      3042.67     3675.42      90.000    TOP
VIA9      3345.82     2855.34      90.000    TOP
VIA10     3281.82     2982.27      90.000    TOP
VIA11     3345.82     3108.24      90.000    TOP
VIA12     3281.82     3234.24      90.000    TOP
VIA13     3281.82     3486.21      90.000    TOP
VIA14     3345.82     3360.21      90.000    TOP
VIA15     3345.82     3612.24      90.000    TOP
VIA16     3281.82     3737.68      90.000    TOP
VIA17     8036.00     3354.00     135.000    TOP
VIA18     7934.00     3377.00     135.000    TOP
VIA19     7815.00     3495.00     135.000    TOP
VIA20     7764.18     3372.00     135.000    TOP
VIA21     7652.00     3306.00     135.000    TOP
VIA22     7643.18     3492.00     135.000    TOP
VIA23     7536.00     3425.00     135.000    TOP
VIA24     7475.00     3315.00     135.000    TOP
VIA25     3042.31     2667.98      90.000    TOP
VIA26     8215.80     3322.59     135.000    TOP
VIA41     8500.00     3120.00     315.000    TOP
VIA42     8545.00     2965.00     315.000    TOP
VIA43     8485.00     2905.00     315.000    TOP
VIA44     8430.00     2850.00     315.000    TOP
VIA45     8450.00     2720.00     315.000    TOP
VIA46     8390.00     2662.00     315.000    TOP
VIA47     8332.00     2597.00     315.000    TOP
VIA48     8325.36     2500.81     315.000    TOP
X1        3646.61     6488.49     180.000    TOP
X2        2751.33     6152.67     180.000    TOP

EOS

#From(Function(Sicard.Report) Version 3.0)